G04 ================== begin FILE IDENTIFICATION RECORD ==================*
G04 Layout Name:  F:/<user>/2022/FB/R4006-TIMING/brd/gerber-3/R4006-B0001-02_R01.brd*
G04 Film Name:    R4006-B0001-02_R01_L03*
G04 File Format:  Gerber RS274X*
G04 File Origin:  Cadence Allegro 17.2-S079*
G04 Origin Date:  Fri Feb 25 18:14:43 2022*
G04 *
G04 Layer:  ETCH/L03_SIG1*
G04 Layer:  PIN/L03_SIG1*
G04 Layer:  VIA CLASS/L03_SIG1*
G04 Layer:  MANUFACTURING/L03_SIG1*
G04 Layer:  MANUFACTURING/CELESTICA_LEGEND*
G04 *
G04 Offset:    (0.00 0.00)*
G04 Mirror:    No*
G04 Mode:      Positive*
G04 Rotation:  0*
G04 FullContactRelief:  No*
G04 UndefLineWidth:     6.00*
G04 ================== end FILE IDENTIFICATION RECORD ====================*
%FSLAX55Y55*MOIN*%
%IR0*IPPOS*OFA0.00000B0.00000*MIA0B0*SFA1.00000B1.00000*%
%ADD10C,.02*%
%ADD11C,.024*%
%ADD12C,.018*%
%ADD13C,.1*%
%ADD14C,.01*%
%ADD15C,.015*%
%ADD16C,.004*%
%ADD17C,.006*%
%ADD18C,.005*%
%ADD19C,.0062*%
%ADD20C,.06004*%
%ADD21C,.05804*%
G75*
%LPD*%
G75*
G36*
G01X99867Y276500D02*
X107000D01*
X110658Y272842D01*
X109908Y272092D01*
G03X109248Y270500I1592J-1593D01*
G01Y253249D01*
X107000Y251000D01*
X91603D01*
G03X87597I-2003J-2100D01*
G01X86603D01*
G03X84600Y251802I-2003J-2100D01*
G03X82653Y251052I0J-2902D01*
G01X82596Y251000D01*
X82012D01*
Y251293D01*
X82083Y251353D01*
G03X83150Y253648I-1935J2295D01*
G03X77146I-3002J0D01*
G03X77839Y251729I3002J0D01*
G02X77782Y251162I-308J-255D01*
G03X77597Y251000I1818J-2262D01*
G01X68089D01*
G02X67690Y251435I0J400D01*
G03X67702Y251700I-2990J268D01*
G03X64700Y254702I-3002J0D01*
G03X63775Y254556I0J-3003D01*
G02X63252Y254936I-123J380D01*
G01Y261017D01*
G03X62622Y262579I-2251J0D01*
G01Y270791D01*
G02X63116Y271180I400J0D01*
G03X63800Y271098I685J2820D01*
G03X66702Y274000I0J2902D01*
G03X66039Y275846I-2901J0D01*
G02X66348Y276500I309J254D01*
G01X73032D01*
G02X73367Y275882I0J-400D01*
G03X72915Y274617I2433J-1582D01*
G02X72455Y274266I-397J44D01*
G03X72000Y274302I-456J-2866D01*
G03Y268498I0J-2902D01*
G03X74885Y271083I0J2902D01*
G02X75345Y271434I397J-44D01*
G03X75800Y271398I456J2866D01*
G03X78702Y274300I0J2902D01*
G03X78233Y275882I-2903J0D01*
G02X78568Y276500I335J218D01*
G01X80921D01*
G02X81112Y275749I0J-400D01*
G03X79598Y273200I1389J-2549D01*
G03X85402I2902J0D01*
G03X83888Y275749I-2903J0D01*
G02X84079Y276500I191J351D01*
G01X91933D01*
X93375Y275058D01*
G03X94967Y274398I1593J1592D01*
G01X95797D01*
G02X96150Y273811I0J-400D01*
G03X95798Y272400I2650J-1411D01*
G03X96558Y270403I3002J-1D01*
G03X95698Y268300I2141J-2103D01*
G03X101702I3002J0D01*
G03X100942Y270297I-3002J1D01*
G03X101802Y272400I-2141J2103D01*
G03X99534Y275311I-3002J0D01*
G02X99349Y275982I98J388D01*
G01X99867Y276500D01*
G37*
G36*
G01X156500Y419000D02*
X169500D01*
X171500Y417000D01*
Y379500D01*
X169000Y377000D01*
X156500D01*
X154000Y379500D01*
Y386196D01*
G03X154002Y386300I-2900J108D01*
G03X154000Y386404I-2902J-4D01*
G01Y387637D01*
X154155Y387673D01*
G03X154377Y387734I-657J2826D01*
G02X154898Y387358I121J-381D01*
G03X157900Y384398I3002J42D01*
G03Y390402I0J3002D01*
G03X156929Y390241I-1J-3002D01*
G02X156400Y390605I-129J378D01*
G03X155369Y392720I-2900J-105D01*
G03X156052Y394590I-2218J1870D01*
G03X154622Y397091I-2902J0D01*
G02X154495Y397661I203J344D01*
G03X155002Y399300I-2396J1639D01*
G03X154000Y401494I-2903J0D01*
G01Y404777D01*
G03Y407823I-2469J1523D01*
G01Y409371D01*
G03X154702Y411300I-2299J1929D01*
G03X154044Y413176I-3003J0D01*
G01X154000Y413231D01*
Y414024D01*
G03X155102Y416300I-1799J2276D01*
G03X154934Y417273I-2902J0D01*
G01X154892Y417392D01*
X156500Y419000D01*
G37*
G36*
G01X328500Y425100D02*
X341500D01*
X344000Y422600D01*
Y418239D01*
G03X342998Y416000I2001J-2239D01*
G03X343937Y413819I3002J0D01*
G01X344000Y413760D01*
Y413300D01*
G02X343612Y412901I-400J1D01*
G03Y406899I88J-3001D01*
G02X344000Y406500I-12J-400D01*
G01Y391306D01*
G03X343998Y391200I3000J-110D01*
G03X344000Y391094I3002J4D01*
G01Y381000D01*
X342003Y379003D01*
X341923Y379001D01*
G03X340386Y378531I77J-3001D01*
G01X340337Y378500D01*
X340163D01*
X340114Y378531D01*
G03X338500Y379002I-1614J-2530D01*
G03X336838Y378500I0J-3002D01*
G01X333162D01*
G03X329838I-1662J-2500D01*
G01X328000D01*
X326000Y380500D01*
Y384277D01*
X326144Y384319D01*
G03X328302Y387200I-844J2881D01*
G03X327436Y389309I-3001J0D01*
G02Y389591I142J141D01*
G03Y393809I-2135J2109D01*
G02Y394091I142J141D01*
G03X328302Y396200I-2135J2109D01*
G03X326144Y399081I-3002J0D01*
G01X326000Y399123D01*
Y401394D01*
G03X326002Y401500I-3000J110D01*
G03X326000Y401606I-3002J-4D01*
G01Y407948D01*
G03X327802Y410700I-1200J2752D01*
G03X326936Y412809I-3001J0D01*
G02Y413091I142J141D01*
G03X327802Y415200I-2135J2109D01*
G03X326000Y417952I-3002J0D01*
G01Y422600D01*
X328500Y425100D01*
G37*
G36*
G01X572345Y221500D02*
X577000D01*
X577500Y221000D01*
Y208000D01*
X576500Y207000D01*
X574512D01*
G03X571888I-1312J-2699D01*
G01X570012D01*
G03X568700Y207302I-1312J-2699D01*
G03X567427Y207019I-1J-3002D01*
G01X567387Y207000D01*
X566202D01*
X566156Y207025D01*
G03X564700Y207402I-1456J-2625D01*
G03X563199Y207000I0J-3003D01*
G01X545739D01*
G03X541261I-2239J-2001D01*
G01X536500D01*
X535000Y208500D01*
Y216500D01*
X537500Y219000D01*
X558000D01*
X559500Y217500D01*
X565288D01*
G03X568612I1662J2500D01*
G01X570000D01*
X571000Y218500D01*
Y220490D01*
G03X572345Y221500I-1058J2809D01*
G37*
G36*
G01X566712Y242000D02*
X577500D01*
X580500Y239000D01*
Y229000D01*
X578500Y227000D01*
X575000D01*
X572994Y224994D01*
G02X572386Y225045I-282J283D01*
G03X569943Y226302I-2443J-1746D01*
G01X569909D01*
G02X569516Y226798I-5J400D01*
G03X569602Y227500I-2816J701D01*
G03X563798I-2902J0D01*
G03X566666Y224598I2902J0D01*
G02X567048Y224093I-4J-400D01*
G03X566941Y223300I2895J-794D01*
G03X568198Y220857I3003J0D01*
G02X568249Y220249I-232J-326D01*
G01X567502Y219502D01*
X561498D01*
X555263Y225737D01*
G02X555257Y226014I141J142D01*
G03X556024Y227979I-2134J1965D01*
G03X554500Y230533I-2902J0D01*
G01Y237000D01*
X554911Y237411D01*
X554948Y237426D01*
G03X556574Y239052I-1148J2774D01*
G01X556589Y239089D01*
X559500Y242000D01*
X564088D01*
G03X566712I1312J2699D01*
G37*
%LPC*%
G75*
G36*
G01X101197Y257979D02*
G02X101502Y256661I-2697J-1318D01*
G02X95498I-3002J0D01*
G02X96303Y258707I3003J0D01*
G02X95998Y260025I2697J1318D01*
G02X102002I3002J0D01*
G02X101197Y257979I-3003J0D01*
G37*
G36*
G01X77634Y263688D02*
G02X76346Y266100I1614J2412D01*
G02X82150I2902J0D01*
G02X79733Y263239I-2902J0D01*
G03X79578Y262512I67J-394D01*
G02X80139Y262022I-1613J-2413D01*
G03X80763Y262053I300J265D01*
G02X82731Y263265I2437J-1753D01*
G02X82698Y263700I2869J436D01*
G02X88502I2902J0D01*
G02X87820Y261831I-2902J0D01*
G03X88017Y261189I306J-257D01*
G02X90202Y258300I-817J-2889D01*
G02X87200Y255298I-3002J0D01*
G02X84364Y257316I0J3002D01*
G03X84114Y257441I-189J-66D01*
G02X83200Y257298I-915J2859D01*
G02X80904Y258366I0J3002D01*
G03X80279Y258350I-306J-257D01*
G02X77964Y257198I-2315J1750D01*
G02X75062Y260100I0J2902D01*
G02X77479Y262961I2902J0D01*
G03X77634Y263688I-67J394D01*
G37*
G54D20*
X72400Y264600D03*
X69500Y257800D03*
X158500Y405200D03*
X340500Y391600D03*
G54D21*
X167100Y405600D03*
X566600Y212900D03*
X559500Y228000D03*
%LPD*%
G75*
G54D10*
X9000Y279000D03*
Y286000D03*
X19100Y148798D03*
X15000Y279000D03*
X41500Y127500D03*
X41409Y132591D03*
X41600Y148798D03*
X32600Y148700D03*
X44500Y309000D03*
X39500D03*
X34500D03*
X62500Y100500D03*
X56500Y113000D03*
X46500Y133000D03*
X62000Y307000D03*
Y323500D03*
X73500Y112500D03*
X67000Y109000D03*
X64500Y129500D03*
X75000Y141700D03*
X64700Y251700D03*
X68000Y235500D03*
X67700Y240200D03*
X64248Y258000D03*
X64500Y296750D03*
X78000Y291500D03*
X66000Y318500D03*
Y323500D03*
X79500Y341790D03*
X80500Y420500D03*
X84200Y75000D03*
X96500Y98000D03*
X92250Y97750D03*
X93500Y110500D03*
X90500Y105000D03*
X96500Y140000D03*
X91500D03*
X93900Y155200D03*
X88500Y149000D03*
X95500Y192000D03*
X97500Y214000D03*
X96000Y241000D03*
X85700Y236500D03*
X86900Y267200D03*
X82500Y339000D03*
X97500Y341000D03*
X91500Y359500D03*
X83500Y360000D03*
X99000Y175500D03*
Y188500D03*
Y206500D03*
X112500Y290000D03*
X102500D03*
X105410Y318500D03*
X101500Y341000D03*
X104019Y347425D03*
X99500Y370000D03*
X126000Y72000D03*
X129000Y321500D03*
X130000Y349664D03*
X140100Y306900D03*
X135000Y312000D03*
X146000Y334000D03*
X141000Y379500D03*
X159100Y382600D03*
X163600Y378600D03*
X160582Y410000D03*
X160550Y413400D03*
X201700Y327900D03*
X213500Y54000D03*
X207800Y83010D03*
X229582Y48918D03*
X225500Y347500D03*
X230000D03*
X307500Y160500D03*
X303500Y164000D03*
X312500Y160500D03*
X324000Y227500D03*
X312500Y225400D03*
X311900Y229900D03*
X323500Y263000D03*
X312000Y269000D03*
Y256500D03*
Y264500D03*
X312500Y307500D03*
X310600Y326000D03*
X325000Y363000D03*
X336000Y61060D03*
X340500Y87000D03*
X338000Y102500D03*
X327923Y221577D03*
X335153Y217875D03*
X330500Y265000D03*
X337500D03*
X341400Y323500D03*
X339200Y380300D03*
X339300Y384000D03*
Y387700D03*
X336300Y423200D03*
Y415200D03*
Y419200D03*
X340800Y415200D03*
X349500Y61000D03*
X354500Y60920D03*
X345500Y87000D03*
X354000Y82500D03*
X344000Y103000D03*
X346500Y174000D03*
X344500Y181500D03*
Y265000D03*
X346000Y306500D03*
X351000Y308000D03*
X355000Y337000D03*
X348418Y361300D03*
X362000Y123500D03*
Y128000D03*
X374600Y178200D03*
X373649Y185735D03*
X371000Y326000D03*
X370000Y337000D03*
X360700Y406200D03*
X364500Y413500D03*
X386000Y246800D03*
X380100D03*
X392500Y329100D03*
Y323900D03*
X395000Y370000D03*
Y360000D03*
X383900Y384600D03*
X379500Y381000D03*
Y375800D03*
Y417500D03*
X402000Y303000D03*
X407500Y300500D03*
X402500Y308000D03*
X408500Y316500D03*
Y311000D03*
X398000Y336500D03*
X411840Y353620D03*
X417500Y75000D03*
X429000Y123500D03*
X418500Y117000D03*
X415000Y123500D03*
X420900Y246800D03*
X413000Y300500D03*
X417500Y337000D03*
X422500Y354500D03*
X428500Y346000D03*
X420500Y366000D03*
X425000Y381000D03*
X423500Y415500D03*
X436500Y237500D03*
X439000Y302000D03*
X434500D03*
X438400Y382400D03*
X430000Y381000D03*
X460000Y76000D03*
X448500Y237500D03*
X457000Y258500D03*
X459500Y262000D03*
X461500Y268409D03*
Y311000D03*
X453500Y381500D03*
X466500Y110400D03*
X471200Y115700D03*
X476800Y120700D03*
X468500Y270000D03*
X481000Y341000D03*
X482800Y110300D03*
X497000Y154000D03*
X498060Y185500D03*
X492500Y226000D03*
X497500D03*
X497000Y341000D03*
X513200Y66000D03*
X508000Y105500D03*
Y110500D03*
Y115500D03*
X507000Y192500D03*
Y188500D03*
X509000Y340500D03*
X504500D03*
X522500Y114500D03*
X526000Y295500D03*
X530000Y406500D03*
X522100Y416500D03*
X544300Y87100D03*
X541000Y96000D03*
X545800Y216500D03*
X541000Y216400D03*
X546500Y240500D03*
X541000Y281500D03*
X542000Y296450D03*
X537500Y304000D03*
X548829Y416329D03*
X566950Y220000D03*
X560000Y240000D03*
X562000Y254870D03*
X554400Y267500D03*
X560000Y342100D03*
X555000Y402000D03*
X567126Y417500D03*
X555315D03*
X586500Y107000D03*
Y112500D03*
X571000Y217900D03*
X576500Y219700D03*
X578900Y236600D03*
X583000Y297000D03*
X578937Y417500D03*
X587000Y184000D03*
X604000Y398000D03*
X602559Y417500D03*
X614370D03*
X622000Y141500D03*
Y162000D03*
Y151600D03*
Y181500D03*
X633000Y286500D03*
G54D11*
X29922Y340080D03*
X33466D03*
X38782Y343150D03*
X35238D03*
G54D12*
G01X129000Y321500D02*
X108410D01*
X105410Y318500D01*
G01X130000Y349664D02*
X124986Y344650D01*
X124752D01*
X124702Y344600D01*
X122298D01*
X122248Y344650D01*
X119850D01*
X117075Y347425D01*
X104019D01*
X73600Y252500D03*
X68600Y274000D03*
X70500Y419000D03*
X75580Y419004D03*
X87100Y271300D03*
X131500Y290500D03*
X148500Y62500D03*
X139500D03*
X136000Y290500D03*
X138250Y372250D03*
X138500Y387500D03*
X163300Y382900D03*
X160600Y417400D03*
X180620Y77890D03*
X203000Y75000D03*
X207880Y78740D03*
X214810Y78810D03*
X263300Y52200D03*
X307300Y61300D03*
X318000Y268500D03*
X310600Y335000D03*
X327500Y232000D03*
X332600Y246600D03*
X334350Y282000D03*
X336500Y295000D03*
X341500Y333500D03*
X349000Y82500D03*
X352300Y175000D03*
X344000Y295000D03*
X355000Y328000D03*
X383128Y178372D03*
X391130Y182374D03*
X387193Y186311D03*
X406879Y158753D03*
X410816Y170564D03*
X395067Y182374D03*
X399005Y186311D03*
Y190248D03*
X410816Y182374D03*
Y190248D03*
Y209933D03*
X426564Y178437D03*
X414753Y182374D03*
Y205996D03*
Y209933D03*
X442311Y143005D03*
Y146942D03*
X438374Y135130D03*
X434437Y146942D03*
X438374D03*
X434437Y150879D03*
X442311D03*
X438374Y190248D03*
X434437Y182374D03*
X438374Y205996D03*
X442311Y209933D03*
X434437Y202059D03*
Y213870D03*
X443000Y386500D03*
X432000Y396500D03*
X454122Y158753D03*
Y162690D03*
X461996Y170564D03*
Y178437D03*
X458060Y170564D03*
X461996Y166627D03*
X458059Y190248D03*
X465933Y170564D03*
Y178437D03*
X469870Y190248D03*
X473807Y182374D03*
X469870D03*
X490970Y133500D03*
Y138500D03*
X533000Y95000D03*
Y99500D03*
X528500Y299000D03*
X577100Y227900D03*
X576200Y342500D03*
X601902Y200100D03*
X590500Y301500D03*
X633000Y267000D03*
G54D13*
X126067Y104043D03*
X253967Y93443D03*
X265967D03*
X277867D03*
G54D14*
G01X136000Y-65500D02*
Y-158000D01*
X506000D01*
Y-65500D01*
X136000D01*
G01X316000D02*
Y-158000D01*
G54D15*
G01X68000Y235500D02*
X69000Y236500D01*
X71870D01*
X82920Y225450D01*
X88880D01*
X92280Y228850D01*
Y237280D01*
X96000Y241000D01*
G01X67700Y240200D02*
X82000D01*
X85700Y236500D01*
G01X140100Y306900D02*
X138450Y305250D01*
X138202D01*
X136252Y303300D01*
X118300D01*
X110500Y295500D01*
X96304D01*
X96054Y295250D01*
X92850D01*
X89100Y291500D01*
X78000D01*
G01X141000Y379500D02*
Y374500D01*
X142500Y373000D01*
X166000D01*
X167500Y371500D01*
X180000D01*
X183500Y375000D01*
X279500D01*
X291500Y363000D01*
X325000D01*
G01X336000Y61060D02*
X335560Y61500D01*
X312000D01*
X307500Y57000D01*
X289891D01*
X288391Y58500D01*
X257500D01*
X252500Y53500D01*
X214000D01*
X213500Y54000D01*
G01X310600Y335000D02*
X307400Y331800D01*
Y327600D01*
X309000Y326000D01*
X310600D01*
G01X341400Y323500D02*
X350500D01*
X355000Y328000D01*
G01Y337000D02*
X356500D01*
X358000Y335500D01*
X368500D01*
X370000Y337000D01*
G01X355000Y328000D02*
X355500Y327500D01*
X369500D01*
X371000Y326000D01*
G01X348418Y361300D02*
X364500Y377382D01*
Y413500D01*
G01X343000Y402000D02*
X352000D01*
X356200Y406200D01*
X360700D01*
G01X398000Y336500D02*
X397000Y335500D01*
X387000D01*
X385500Y337000D01*
X370000D01*
G01X383900Y384600D02*
X389100D01*
X391000Y386500D01*
X397500D01*
X401000Y383000D01*
Y381500D01*
X405500Y377000D01*
X433000D01*
X438400Y382400D01*
G01X379500Y417500D02*
X390400Y428400D01*
X532900D01*
X535000Y430500D01*
X613000D01*
X619000Y424500D01*
Y413000D01*
X604000Y398000D01*
G01X417500Y337000D02*
X415000Y334500D01*
X404500D01*
X402500Y336500D01*
X398000D01*
G01X423500Y415500D02*
X426500Y412500D01*
Y400000D01*
X430000Y396500D01*
X432000D01*
G01X438400Y382400D02*
X438900D01*
X443000Y386500D01*
G01X453500Y381500D02*
X448000D01*
X443000Y386500D01*
G01D02*
X442000D01*
X432000Y396500D01*
G01D02*
X436500Y401000D01*
Y415000D01*
X447000Y425500D01*
X509500D01*
X518500Y416500D01*
X522100D01*
G01X604000Y398000D02*
X600000Y394000D01*
X578000D01*
X574000Y390000D01*
Y376000D01*
X572500Y374500D01*
Y356500D01*
X579500Y349500D01*
Y327700D01*
X591200Y316000D01*
X637700D01*
X642800Y310900D01*
Y255800D01*
X638000Y251000D01*
Y230000D01*
X633000Y225000D01*
Y211501D01*
X630500Y209001D01*
Y195984D01*
X650500Y175984D01*
Y97000D01*
X641000Y87500D01*
Y86500D01*
X629000Y74500D01*
X600500D01*
X585000Y90000D01*
X569000D01*
X565500Y93500D01*
X550700D01*
X544300Y87100D01*
G01X545800Y216500D02*
X544000Y218300D01*
G01D02*
Y230500D01*
X546500Y233000D01*
Y240500D01*
G01X541000Y281500D02*
Y280900D01*
X554400Y267500D01*
G01X542000Y296450D02*
X542250Y296200D01*
Y283950D01*
X541000Y282700D01*
Y281500D01*
G01X537500Y304000D02*
X537036Y303536D01*
Y301414D01*
X542000Y296450D01*
G01X562000Y254870D02*
Y259900D01*
X554400Y267500D01*
G01X560000Y342100D02*
X560400Y342500D01*
X576200D01*
G01X555000Y402000D02*
X558000Y405000D01*
X561304D01*
X566054Y400250D01*
X601750D01*
X604000Y398000D01*
G54D16*
G01X38782Y338582D02*
Y343150D01*
G01X33466Y340080D02*
X30120Y342013D01*
G02X29920Y342360I201J347D01*
G01Y344017D01*
G02X30346Y345046I1456J0D01*
G01X438374Y146942D02*
X436500Y145068D01*
Y130000D01*
G01X442311Y143005D02*
X443811Y141505D01*
Y132420D01*
G01X457580Y128600D02*
X456040Y130140D01*
Y147720D01*
X454790Y148970D01*
X444339D01*
X442311Y146942D01*
G01X440500Y212560D02*
Y209000D01*
X438374Y206874D01*
Y205996D01*
G54D17*
G01X145964Y-110118D02*
G03I-634J0D01*
G01X149695D02*
G03I-1038J0D01*
G01X168013Y-137456D02*
G03I-634J0D01*
G01X155900Y-133655D02*
G03I-632J0D01*
G01X161735Y-128639D02*
G03I-1458J0D01*
G01X158530Y-131428D02*
G03I-1041J0D01*
G01X158461Y-119126D02*
G03I-1283J0D01*
G01X162690Y-117490D02*
G03I-1584J0D01*
G01X169809Y-121292D02*
G03I-2180J0D01*
G01X165531Y-125255D02*
G03I-1869J0D01*
G01X167813Y-115513D02*
G03I-1971J0D01*
G01X154775Y-120500D02*
G03I-892J0D01*
G01X162681Y-102774D02*
G03I-1584J0D01*
G01X158451Y-101149D02*
G03I-1283J0D01*
G01X159258Y-110118D02*
G03I-1868J0D01*
G01X169812Y-98951D02*
G03I-2180J0D01*
G01X167802Y-104739D02*
G03I-1971J0D01*
G01X165183Y-110118D02*
G03I-2180J0D01*
G01X171881D02*
G03I-2642J0D01*
G01X152135Y-98681D02*
G03I-632J0D01*
G01X154064Y-110118D02*
G03I-1460J0D01*
G01X154764Y-99775D02*
G03I-892J0D01*
G01X158530Y-88809D02*
G03I-1041J0D01*
G01X161742Y-91601D02*
G03I-1458J0D01*
G01X165531Y-94981D02*
G03I-1869J0D01*
G01X171080Y-131739D02*
G03I-1282J0D01*
G01X169322Y-135033D02*
G03I-892J0D01*
G01X180669Y-131528D02*
G03I-1870J0D01*
G01X180255Y-136311D02*
G03I-1456J0D01*
G01X179841Y-140261D02*
G03I-1042J0D01*
G01X179433Y-143587D02*
G03I-634J0D01*
G01X181439Y-119680D02*
G03I-2640J0D01*
G01X175373Y-123081D02*
G03I-1968J0D01*
G01X173018Y-127816D02*
G03I-1584J0D01*
G01X174681Y-116876D02*
G03I-2640J0D01*
G01X180979Y-125917D02*
G03I-2180J0D01*
G01X186177Y-123075D02*
G03I-1971J0D01*
G01X188199Y-116876D02*
G03I-2640J0D01*
G01X175452Y-97124D02*
G03I-1968J0D01*
G01X186225Y-97178D02*
G03I-1971J0D01*
G01X181439Y-100556D02*
G03I-2640J0D01*
G01X174681Y-103361D02*
G03I-2640J0D01*
G01X188199D02*
G03I-2640J0D01*
G01X179841Y-79975D02*
G03I-1042J0D01*
G01X171217Y-88444D02*
G03I-1282J0D01*
G01X173123Y-92378D02*
G03I-1584J0D01*
G01X180255Y-83924D02*
G03I-1456J0D01*
G01X180669Y-88708D02*
G03I-1870J0D01*
G01X180979Y-94320D02*
G03I-2180J0D01*
G01X179433Y-76648D02*
G03I-634J0D01*
G01X191096Y-134658D02*
G03I-892J0D01*
G01X192135Y-136781D02*
G03I-631J0D01*
G01X198775Y-128635D02*
G03I-1458J0D01*
G01X195808Y-125255D02*
G03I-1869J0D01*
G01X200547Y-113952D02*
G03X203345Y-117196I7247J3422D01*
G01X192148Y-121285D02*
G03I-2180J0D01*
G01X187928Y-127802D02*
G03I-1584J0D01*
G01X189667Y-131511D02*
G03I-1283J0D01*
G01X200699Y-105836D02*
G03X200547Y-113953I8974J-4228D01*
G01X208284Y-101612D02*
G03X200698Y-105835I-219J-8531D01*
G01X192148Y-98951D02*
G03I-2180J0D01*
G01X191108Y-82727D02*
G03I-634J0D01*
G01X190184Y-85250D02*
G03I-893J0D01*
G01X195808Y-94981D02*
G03I-1869J0D01*
G01X187839Y-92457D02*
G03I-1584J0D01*
G01X189190Y-88538D02*
G03I-1283J0D01*
G01X214259Y-115661D02*
G03X213314Y-114453I-714J415D01*
G01X202049Y-108260D02*
G03X205722Y-116181I7039J-1548D01*
G01X218075Y-112869D02*
G03X219083Y-115752I4343J-99D01*
G01X208854Y-116658D02*
G03X213313Y-114452I-2485J10632D01*
G01X208470Y-118462D02*
G03X214261Y-115663I-1122J9711D01*
G01X203346Y-117195D02*
G03X208470Y-118461I4545J7394D01*
G01X205721Y-116179D02*
G03X208853Y-116659I2561J6250D01*
G01X215903Y-114020D02*
G03X219079Y-118061I6190J1597D01*
G01X215904Y-114020D02*
Y-111835D01*
G01X227413Y-112869D02*
X218074D01*
G01X214175Y-103951D02*
G03X208283Y-101613I-6403J-7542D01*
G01X213150Y-105147D02*
G03X214175Y-103951I410J686D01*
G01X213152Y-105146D02*
G03X208030Y-103430I-5122J-6786D01*
G01X208029Y-103429D02*
G03X202049Y-108259I-48J-6058D01*
G01X225189Y-111399D02*
G03X218071I-3559J159D01*
G01X218070Y-111418D02*
Y-111399D01*
G01X225188Y-111418D02*
X218070D01*
G01X227412Y-111835D02*
G03X215906I-5753J223D01*
G01X230059Y-117625D02*
Y-102034D01*
G01X230060Y-117626D02*
G03X232080I1010J239D01*
G01X226590Y-116472D02*
G03X225311Y-115210I-817J451D01*
G01X234673Y-114020D02*
G03X237849Y-118061I6190J1597D01*
G01X232081Y-102041D02*
Y-117625D01*
G01X219083Y-115753D02*
G03X225311Y-115211I2844J3371D01*
G01X219079Y-118060D02*
G03X226591Y-116473I2662J5972D01*
G01X227413Y-111835D02*
Y-112869D01*
G01X232080Y-102041D02*
G03X230060Y-102034I-1011J-236D01*
G01X225188Y-111399D02*
Y-111418D01*
G01X234675Y-114020D02*
Y-111835D01*
G01X246181D02*
G03X234675I-5753J223D01*
G01X252849Y-116771D02*
G03X254892Y-115895I-74J2994D01*
G01X236844Y-112869D02*
G03X237852Y-115752I4343J-99D01*
G01X237848Y-118060D02*
G03X245360Y-116473I2662J5972D01*
G01X245358Y-116472D02*
G03X244079Y-115210I-817J451D01*
G01X237852Y-115753D02*
G03X244080Y-115211I2844J3371D01*
G01X249566Y-115529D02*
G03X252307Y-116760I2985J2980D01*
G01Y-116761D02*
G03X252849Y-116772I366J4691D01*
G01X250282Y-118087D02*
G03X254318Y-118340I2605J9244D01*
G01X247897Y-116444D02*
G03X250283Y-118086I3752J2898D01*
G01X249568Y-115529D02*
G03X247898Y-116443I-748J-616D01*
G01X255608Y-108618D02*
G03X253612Y-107689I-3116J-4086D01*
G01X246181Y-111835D02*
Y-112869D01*
G01D02*
X236844D01*
G01X255002Y-114328D02*
G03X252723Y-112986I-3540J-3405D01*
G01X249955Y-112030D02*
G03X252723Y-112985I8208J19302D01*
G01X243957Y-111399D02*
Y-111418D01*
G01X243958Y-111399D02*
G03X236840I-3559J159D01*
G01X236841Y-111418D02*
Y-111399D01*
G01X243957Y-111418D02*
X236841D01*
G01X248537Y-109748D02*
G03X249956Y-112031I2652J66D01*
G01X248537Y-108250D02*
Y-109748D01*
G01X250179Y-106359D02*
G03X248537Y-108249I2747J-4045D01*
G01X256884Y-107368D02*
G03X250178Y-106359I-4153J-4811D01*
G01X253611Y-107689D02*
G03X251080Y-107949I-869J-3992D01*
G01X251081Y-107948D02*
G03X250837Y-110104I805J-1183D01*
G01Y-110106D02*
G03X254306Y-111513I5270J8013D01*
G01X260954Y-116041D02*
Y-107954D01*
G01X254892Y-115895D02*
G03X255001Y-114328I-764J840D01*
G01X269619Y-117484D02*
Y-106797D01*
G01X269620Y-117484D02*
G03X271926I1153J198D01*
G01X266864Y-117375D02*
G03X266002Y-116329I-764J249D01*
G01X262978Y-115462D02*
G03X266002Y-116329I2046J1428D01*
G01X260955Y-116043D02*
G03X264164Y-118351I2956J725D01*
G01X265463Y-118350D02*
X264165D01*
G01X265464Y-118352D02*
G03X266864Y-117374I-24J1525D01*
G01X256906Y-116470D02*
G03X257054Y-113728I-3143J1545D01*
G01X254317Y-118340D02*
G03X256906Y-116470I-1259J4470D01*
G01X262978Y-107954D02*
Y-115463D01*
G01X257054Y-113729D02*
G03X254307Y-111513I-3470J-1490D01*
G01X271969Y-102342D02*
G03I-1194J0D01*
G01X271926Y-106797D02*
G03X269620I-1153J-409D01*
G01X266003Y-107954D02*
X262978D01*
G01X266004Y-107955D02*
G03X266008Y-105932I-177J1012D01*
G01X262978D02*
X266008D01*
G01X262971Y-103419D02*
X262978Y-105932D01*
G01X262972Y-103418D02*
G03X260954Y-103491I-1005J-141D01*
G01Y-105932D02*
Y-103492D01*
G01X259930Y-105932D02*
X260954D01*
G01X259930D02*
G03X259981Y-107955I298J-1005D01*
G01X260954Y-107954D02*
X259982D01*
G01X255606Y-108620D02*
G03X256885Y-107367I599J667D01*
G01X290671Y-110842D02*
G03X290703Y-118351I860J-3751D01*
G01X276837Y-114305D02*
G03X278891Y-116297I4069J2141D01*
G01X274529Y-113568D02*
G03X275888Y-116443I5718J944D01*
G01X275887D02*
G03X279572Y-118352I4392J3967D01*
G01X281425Y-118350D02*
X279571D01*
G01X281425D02*
G03X284525Y-117161I0J4636D01*
G01X285201Y-116508D02*
X284524Y-117161D01*
G01X285201Y-116508D02*
G03X283966Y-115211I-695J574D01*
G01X281510Y-116675D02*
G03X283966Y-115212I-989J4453D01*
G01X278889Y-116297D02*
G03X281508Y-116677I1946J4197D01*
G01X271926Y-106797D02*
Y-117484D01*
G01X274529Y-113566D02*
Y-111839D01*
G01X276446Y-112943D02*
G03X276837Y-114305I4162J458D01*
G01X276445Y-112066D02*
Y-112943D01*
G01X283833Y-109274D02*
G03X285403Y-108106I585J852D01*
G01X285402D02*
G03X280919Y-105777I-4776J-3714D01*
G01X279541D02*
X280919D01*
G01X279540D02*
G03X274999Y-109274I1260J-6333D01*
G01X274998D02*
G03X274529Y-111839I9988J-3152D01*
G01X276849Y-109932D02*
G03X276446Y-112066I5467J-2137D01*
G01X280036Y-107542D02*
G03X276849Y-109933I664J-4205D01*
G01X282662Y-108199D02*
G03X280037Y-107539I-2313J-3650D01*
G01X283833Y-109275D02*
G03X282662Y-108202I-9277J-8949D01*
G01X294457Y-116619D02*
G03Y-112289I-51J2165D01*
G01X291853Y-116620D02*
X294456D01*
G01X291853Y-112289D02*
G03Y-116619I195J-2165D01*
G01X294165Y-118350D02*
X290701D01*
G01X294165D02*
G03X296471Y-117226I-1088J5161D01*
G01X296473Y-117625D02*
Y-117226D01*
G01X296474Y-117627D02*
G03X298494I1010J185D01*
G01X298495Y-109394D02*
Y-117625D01*
G01X301067Y-108534D02*
Y-106508D01*
G01X301615Y-108534D02*
X301067D01*
G01X301615Y-106508D02*
Y-108534D01*
G01X302461Y-106508D02*
X301615D01*
G01X302461Y-106001D02*
Y-106508D01*
G01X300223Y-106001D02*
X302461D01*
G01X300223Y-106508D02*
Y-106001D01*
G01X301067Y-106508D02*
X300223D01*
G01X305164Y-106001D02*
X304731D01*
G01X305713Y-108544D02*
X305164Y-106001D01*
G01X305171Y-108544D02*
X305713D01*
G01X304889Y-106871D02*
X305171Y-108544D01*
G01X304309D02*
X304889Y-106871D01*
G01X304086Y-108544D02*
X304309D01*
G01X303501Y-106887D02*
X304086Y-108544D01*
G01X303226D02*
X303501Y-106887D01*
G01X302698Y-108544D02*
X303226D01*
G01X303243Y-106001D02*
X302698Y-108544D01*
G01X303648Y-106001D02*
X303243D01*
G01X304192Y-107632D02*
X303648Y-106001D01*
G01X304731D02*
X304192Y-107632D01*
G01X294456Y-112288D02*
X291853D01*
G01X296473Y-110841D02*
Y-109686D01*
G01X296472Y-110841D02*
G03X292878Y-110536I-3256J-17043D01*
G01X292879Y-110535D02*
G03X290670Y-110842I280J-10112D01*
G01X298496Y-109394D02*
G03X295031Y-105933I-3962J-501D01*
G01X291563Y-105932D02*
X295031D01*
G01X291562D02*
G03X289112Y-107085I584J-4421D01*
G01Y-107086D02*
G03X289820Y-108520I585J-603D01*
G01X290987Y-107954D02*
G03X289821Y-108520I1446J-4464D01*
G01X294740Y-107954D02*
X290987D01*
G01X296473Y-109686D02*
G03X294742Y-107955I-1598J133D01*
G01X381000Y-125000D02*
Y-133000D01*
X385000D01*
G01X391000Y-125000D02*
X390200Y-125267D01*
X389600Y-125933D01*
X389200Y-126733D01*
X388900Y-127800D01*
X388800Y-129000D01*
X388900Y-130200D01*
X389200Y-131267D01*
X389600Y-132067D01*
X390200Y-132733D01*
X391000Y-133000D01*
X391800Y-132733D01*
X392400Y-132067D01*
X392800Y-131267D01*
X393100Y-130200D01*
X393200Y-129000D01*
X393100Y-127800D01*
X392800Y-126733D01*
X392400Y-125933D01*
X391800Y-125267D01*
X391000Y-125000D01*
G01X396800Y-131400D02*
X397400Y-132333D01*
X398200Y-132867D01*
X399100Y-133000D01*
X399900Y-132867D01*
X400700Y-132200D01*
X401200Y-131400D01*
X401300Y-130600D01*
X401100Y-129667D01*
X400400Y-129000D01*
X399700Y-128733D01*
X398800D01*
G01X399700D02*
X400300Y-128333D01*
X400800Y-127667D01*
X401000Y-126867D01*
X400800Y-126067D01*
X400300Y-125400D01*
X399400Y-125000D01*
X398500Y-125133D01*
X397600Y-125667D01*
G01X404000Y-135667D02*
X410000D01*
G01X412900Y-131934D02*
X413700Y-132600D01*
X414600Y-133000D01*
X415400D01*
X416200Y-132600D01*
X416800Y-131934D01*
X417100Y-131000D01*
X416900Y-130067D01*
X416400Y-129267D01*
X415500Y-128733D01*
X414300Y-128467D01*
X413600Y-127933D01*
X413300Y-127000D01*
X413500Y-126067D01*
X414000Y-125400D01*
X414700Y-125000D01*
X415400D01*
X416100Y-125267D01*
X416700Y-125933D01*
G01X421800Y-125000D02*
X424200D01*
G01X423000D02*
Y-133000D01*
G01X421800D02*
X424200D01*
G01X431600Y-129000D02*
X433600D01*
Y-131400D01*
X433000Y-132200D01*
X432300Y-132733D01*
X431300Y-133000D01*
X430300Y-132733D01*
X429600Y-132200D01*
X429000Y-131400D01*
X428600Y-130467D01*
X428400Y-129400D01*
Y-128467D01*
X428600Y-127667D01*
X429000Y-126733D01*
X429600Y-125933D01*
X430200Y-125400D01*
X431000Y-125000D01*
X431700D01*
X432500Y-125267D01*
X433100Y-125800D01*
G01X439000Y-133000D02*
Y-125000D01*
X437800Y-126600D01*
G01Y-133000D02*
X440200D01*
G54D18*
G01X19100Y148798D02*
X35500Y165198D01*
Y258378D01*
X36500Y259378D01*
Y267000D01*
X32750Y270750D01*
X28249D01*
X24999Y274000D01*
X16500D01*
X11500Y279000D01*
X9000D01*
G01Y286000D02*
X12000D01*
X18000Y280000D01*
X29500D01*
X42000Y267500D01*
Y263999D01*
X43000Y262999D01*
Y260000D01*
X40000Y257000D01*
Y247500D01*
X39000Y246500D01*
Y152978D01*
X38500Y152478D01*
Y151898D01*
X41600Y148798D01*
G01X32600Y148700D02*
X37500Y153600D01*
Y258256D01*
X38000Y258756D01*
Y269378D01*
X29378Y278000D01*
X16000D01*
X15000Y279000D01*
G01X41409Y132591D02*
Y145409D01*
X44000Y148000D01*
Y156000D01*
X40500Y159500D01*
Y231000D01*
X45500Y236000D01*
Y256183D01*
X44500Y257183D01*
Y263621D01*
X43500Y264621D01*
Y269073D01*
X26573Y286000D01*
X15147D01*
X13200Y287947D01*
Y315400D01*
X17000Y319200D01*
Y322000D01*
X11500Y327500D01*
Y349000D01*
X19000Y356500D01*
X35000D01*
X50300Y371800D01*
Y417300D01*
X57000Y424000D01*
X77000D01*
X80500Y420500D01*
G01X46500Y133000D02*
X47500D01*
X51500Y137000D01*
Y140500D01*
X58000Y147000D01*
Y186000D01*
X50500Y193500D01*
Y203000D01*
X47250Y206250D01*
Y214750D01*
X48500Y216000D01*
Y246879D01*
X52500Y250879D01*
Y264317D01*
X41000Y275817D01*
Y283499D01*
X30499Y294000D01*
X25400D01*
X21850Y297550D01*
Y311833D01*
X22200Y312183D01*
Y327800D01*
X16500Y333500D01*
Y349500D01*
X20500Y353500D01*
X37000D01*
X50800Y367300D01*
X53300D01*
X55000Y369000D01*
Y413000D01*
X58700Y416700D01*
X68200D01*
X70500Y419000D01*
G01X41500Y127500D02*
Y129499D01*
X43659Y131658D01*
Y144159D01*
X45500Y146000D01*
Y156500D01*
X49000Y160000D01*
Y191500D01*
X45000Y195500D01*
Y202000D01*
X42000Y205000D01*
Y230000D01*
X47000Y235000D01*
Y247501D01*
X51000Y251501D01*
Y256500D01*
X46000Y261500D01*
Y264243D01*
X45000Y265243D01*
Y269695D01*
X20350Y294345D01*
Y312455D01*
X20700Y312805D01*
Y324300D01*
X14500Y330500D01*
Y349878D01*
X19622Y355000D01*
X36000D01*
X51800Y370800D01*
Y414012D01*
X59788Y422000D01*
X72584D01*
X75580Y419004D01*
G01X34500Y309000D02*
X44000Y299500D01*
Y283317D01*
X51567Y275750D01*
X52250D01*
X56920Y271080D01*
Y260080D01*
X58000Y259000D01*
Y253117D01*
X57000Y252117D01*
Y235000D01*
X54500Y232500D01*
Y218000D01*
X56500Y216000D01*
X59500D01*
X60500Y215000D01*
Y204500D01*
X62500Y202500D01*
X67500D01*
X70000Y205000D01*
X86683D01*
X87683Y204000D01*
X100000D01*
X101500Y202500D01*
Y191000D01*
X99000Y188500D01*
G01X44500Y309000D02*
X49500Y304000D01*
Y287500D01*
X60370Y276630D01*
Y261647D01*
X61000Y261017D01*
Y236000D01*
X62500Y234500D01*
Y229634D01*
X63250Y228884D01*
Y220873D01*
X70123Y214000D01*
X97500D01*
G01X99000Y206500D02*
X71000D01*
X65323Y212177D01*
Y216678D01*
X61750Y220251D01*
Y228262D01*
X58500Y231512D01*
Y251495D01*
X59500Y252495D01*
Y260395D01*
X58870Y261025D01*
Y275130D01*
X47000Y287000D01*
Y301500D01*
X39500Y309000D01*
G01X461996Y170564D02*
X464000Y168560D01*
Y165897D01*
X465397Y164500D01*
X466457D01*
X468000Y162957D01*
Y162367D01*
X469617Y160750D01*
X475868D01*
X480470Y156148D01*
Y152270D01*
X488090Y144650D01*
X493519D01*
X497120Y141049D01*
Y130671D01*
X495550Y129101D01*
Y120567D01*
X493000Y118017D01*
Y110950D01*
X485600Y103550D01*
X470480D01*
X467930Y101000D01*
X453000D01*
X450050Y98050D01*
X422150D01*
X419850Y100350D01*
X413200D01*
X410900Y102650D01*
X389108D01*
X387188Y100730D01*
X382580D01*
X380830Y102480D01*
X375905D01*
X374588Y101163D01*
Y98220D01*
X371000Y94632D01*
Y89500D01*
X370250Y88750D01*
X360237D01*
X357987Y91000D01*
X350341D01*
X348091Y93250D01*
X335581D01*
X296831Y132000D01*
X120000D01*
X101000Y113000D01*
X87000D01*
X78150Y104150D01*
X66150D01*
X62500Y100500D01*
G01X56500Y113000D02*
Y114183D01*
X61567Y119250D01*
X65067D01*
X67067Y121250D01*
X67750D01*
X71750Y125250D01*
Y140249D01*
X70500Y141499D01*
Y143000D01*
X76500Y149000D01*
X88500D01*
G01X62000Y323500D02*
X59000Y320500D01*
Y318000D01*
X51500Y310500D01*
Y288622D01*
X60122Y280000D01*
X91617D01*
X94967Y276650D01*
X96833D01*
X100183Y280000D01*
X117572D01*
X124786Y287214D01*
Y291286D01*
X126300Y292800D01*
X136871D01*
X146999Y282672D01*
X286328D01*
X297217Y271783D01*
Y205717D01*
X286800Y195300D01*
Y178700D01*
X297000Y168500D01*
Y158842D01*
X330500Y125342D01*
Y110000D01*
X338000Y102500D01*
G01X66000Y323500D02*
X62040Y319540D01*
Y316540D01*
X53672Y308172D01*
Y289328D01*
X57000Y286000D01*
X75670D01*
X79498Y282172D01*
X116672D01*
X122750Y288250D01*
Y292079D01*
X125471Y294800D01*
X137700D01*
X147828Y284672D01*
X287828D01*
X299217Y273283D01*
Y204718D01*
X288800Y194301D01*
Y180200D01*
X299000Y170000D01*
Y159671D01*
X331550Y127121D01*
X339879D01*
X346000Y121000D01*
X359500D01*
X362000Y123500D01*
G01X66000Y318500D02*
Y316500D01*
X56500Y307000D01*
Y304845D01*
X57000Y304345D01*
X57500D01*
X58000Y303845D01*
Y302345D01*
X57500Y301845D01*
X57000D01*
X56500Y301345D01*
Y299845D01*
X57000Y299345D01*
X58440D01*
X58940Y298845D01*
Y297345D01*
X58440Y296845D01*
X57000D01*
X56500Y296345D01*
Y294499D01*
X62499Y288500D01*
X75999D01*
X79499Y285000D01*
X79755D01*
X79757Y284998D01*
X81539D01*
X81541Y285000D01*
X116500D01*
X120750Y289250D01*
Y292908D01*
X124642Y296800D01*
X138529D01*
X148657Y286672D01*
X289328D01*
X301217Y274783D01*
Y198455D01*
X303250Y196422D01*
Y176750D01*
X301000Y174500D01*
Y160500D01*
X332379Y129121D01*
X340879D01*
X346879Y123121D01*
X357121D01*
X362000Y128000D01*
G01X402500Y308000D02*
X400500Y310000D01*
X388329D01*
X382829Y315500D01*
X349000D01*
X347000Y317500D01*
X335000D01*
X334000Y316500D01*
X309500D01*
X305000Y321000D01*
X287999D01*
X268999Y340000D01*
X235500D01*
X232000Y343500D01*
X222483D01*
X219933Y346050D01*
X210433D01*
X205933Y341550D01*
X176050D01*
X169000Y334500D01*
X151500D01*
X144700Y327700D01*
Y317999D01*
X136201Y309500D01*
X133000D01*
X130300Y312200D01*
X100200D01*
X95900Y307900D01*
X86171D01*
X83871Y305600D01*
X78300D01*
X76900Y307000D01*
X62000D01*
G01X461996Y166627D02*
X464283Y164340D01*
Y162006D01*
X465289Y161000D01*
X466500D01*
X468750Y158750D01*
X475038D01*
X478470Y155318D01*
Y151440D01*
X487260Y142650D01*
X492690D01*
X495120Y140220D01*
Y131780D01*
X491650Y128310D01*
Y125367D01*
X487550Y121267D01*
Y108331D01*
X484769Y105550D01*
X469650D01*
X467300Y103200D01*
X413600D01*
X411570Y105230D01*
X375826D01*
X372588Y101992D01*
Y99088D01*
X369000Y95500D01*
X336160D01*
X297660Y134000D01*
X119171D01*
X100171Y115000D01*
X83500D01*
X78000Y109500D01*
X68500D01*
X68000Y109000D01*
X67000D01*
G01X458060Y170564D02*
X460027Y168597D01*
Y160972D01*
X460696Y160303D01*
X462639D01*
X463546Y159396D01*
Y158575D01*
X465371Y156750D01*
X474208D01*
X476760Y154198D01*
Y150320D01*
X486430Y140650D01*
X491861D01*
X493120Y139391D01*
Y132609D01*
X489511Y129000D01*
X488690D01*
X485550Y125860D01*
Y109160D01*
X483940Y107550D01*
X468820D01*
X466470Y105200D01*
X414800D01*
X412770Y107230D01*
X374671D01*
X372519Y105078D01*
X368239D01*
X366922Y103761D01*
Y102422D01*
X362050Y97550D01*
X336939D01*
X298489Y136000D01*
X118342D01*
X99842Y117500D01*
X83000D01*
X78000Y112500D01*
X73500D01*
G01X434437Y182374D02*
X434374D01*
X431000Y179000D01*
Y154500D01*
X429000Y152500D01*
X427277D01*
X427248Y152529D01*
X417700D01*
X416700Y151529D01*
Y150400D01*
X415270Y148970D01*
X413970D01*
X412600Y147600D01*
Y146500D01*
X411200Y145100D01*
X405601D01*
X404492Y143991D01*
Y142362D01*
X403585Y141455D01*
X401955D01*
X400555Y140055D01*
Y138424D01*
X399631Y137500D01*
X387232D01*
X383000Y133268D01*
Y122129D01*
X373518Y112647D01*
Y112019D01*
X371560Y110061D01*
Y108567D01*
X370243Y107250D01*
X368749D01*
X368577Y107078D01*
X367410D01*
X364922Y104590D01*
Y103423D01*
X361049Y99550D01*
X337768D01*
X299318Y138000D01*
X113500D01*
X108000Y132500D01*
X84200D01*
X75000Y141700D01*
G01X95500Y192000D02*
X93500D01*
X92500Y191000D01*
X89500D01*
X87500Y189000D01*
Y186000D01*
X64500Y163000D01*
Y129500D01*
G01X64700Y251700D02*
X64500Y251500D01*
Y229756D01*
X64750Y229506D01*
Y222467D01*
X71717Y215500D01*
X95500D01*
X96250Y216250D01*
X101250D01*
X103000Y214500D01*
Y189000D01*
X100000Y186000D01*
X91000D01*
X86000Y181000D01*
Y174000D01*
X91500Y168500D01*
Y157600D01*
X93900Y155200D01*
G01X402000Y303000D02*
Y304000D01*
X398500Y307500D01*
X388000D01*
X382000Y313500D01*
X342000D01*
X341250Y312750D01*
X337067D01*
X335317Y314500D01*
X287170D01*
X264170Y337500D01*
X234500D01*
X230950Y341050D01*
X210433D01*
X205933Y336550D01*
X204067D01*
X201067Y339550D01*
X176879D01*
X169829Y332500D01*
X154600D01*
X146700Y324600D01*
Y317170D01*
X137030Y307500D01*
X132171D01*
X129671Y310000D01*
X101800D01*
X97700Y305900D01*
X87000D01*
X84700Y303600D01*
X77471D01*
X76671Y304400D01*
X72150D01*
X64500Y296750D01*
G01X379500Y375800D02*
X376800D01*
X353000Y352000D01*
X286878D01*
X271378Y367500D01*
X190001D01*
X185001Y362500D01*
X139501D01*
X136501Y359500D01*
X121500D01*
X116500Y364500D01*
X113000D01*
X111000Y366500D01*
X102000D01*
X97750Y362250D01*
X82567D01*
X81250Y360933D01*
Y358251D01*
X86000Y353501D01*
Y342290D01*
X85500Y341790D01*
X79500D01*
G01X473807Y182374D02*
X478674D01*
X480300Y184000D01*
X482000D01*
X482750Y183250D01*
X486079D01*
X492000Y177329D01*
Y175327D01*
X495327Y172000D01*
X501501D01*
X510250Y163251D01*
Y142238D01*
X512500Y139988D01*
Y122179D01*
X514999Y119680D01*
Y100000D01*
X509000Y94001D01*
Y88171D01*
X482329Y61500D01*
X417985D01*
X416835Y60350D01*
X373855D01*
X365455Y68750D01*
X324118D01*
X322484Y70384D01*
X306916D01*
X304200Y73100D01*
X293100D01*
X290500Y70500D01*
X263500D01*
X261500Y72500D01*
X255000D01*
X245000Y62500D01*
X229999D01*
X226999Y65500D01*
X213219D01*
X206419Y72300D01*
X193529D01*
X188980Y76849D01*
Y81480D01*
X150960Y119500D01*
X126000D01*
X88500Y82000D01*
Y79300D01*
X84200Y75000D01*
G01X96500Y98000D02*
X97000Y98500D01*
X99001D01*
X126501Y126000D01*
X294244D01*
X333244Y87000D01*
X340500D01*
G01X345500D02*
X343250Y84750D01*
X332650D01*
X293400Y124000D01*
X127500D01*
X99000Y95500D01*
X94500D01*
X92250Y97750D01*
G01X465933Y170564D02*
X468000Y168497D01*
Y165477D01*
X468500Y164977D01*
X474477D01*
X475000Y165500D01*
X478500D01*
X488250Y155750D01*
Y151750D01*
X488750Y151250D01*
X492750D01*
X494540Y149460D01*
Y146459D01*
X499120Y141879D01*
Y129842D01*
X497550Y128272D01*
Y119738D01*
X495000Y117188D01*
Y110121D01*
X486429Y101550D01*
X473050D01*
X469500Y98000D01*
X453500D01*
X451550Y96050D01*
X421320D01*
X419440Y97930D01*
X381101D01*
X374000Y90829D01*
Y87250D01*
X373500Y86750D01*
X359408D01*
X357158Y89000D01*
X349512D01*
X347262Y91250D01*
X334752D01*
X296002Y130000D01*
X122000D01*
X102500Y110500D01*
X93500D01*
G01X417500Y75000D02*
X416000Y76500D01*
Y91000D01*
X411070Y95930D01*
X381930D01*
X376000Y90000D01*
Y83500D01*
X373500Y81000D01*
X362329D01*
X356329Y87000D01*
X348683D01*
X346433Y89250D01*
X333823D01*
X295073Y128000D01*
X123500D01*
X103000Y107500D01*
X93000D01*
X90500Y105000D01*
G01X96500Y140000D02*
X97000D01*
X101553Y144553D01*
Y146446D01*
X113500Y158393D01*
Y269500D01*
X130500Y286500D01*
X132000D01*
X136000Y290500D01*
G01X131500D02*
X111500Y270500D01*
Y159222D01*
X99000Y146722D01*
Y145000D01*
X96500Y142500D01*
X94000D01*
X91500Y140000D01*
G01X88500Y149000D02*
X89000Y148500D01*
X97700D01*
X101000Y151800D01*
Y173500D01*
X99000Y175500D01*
G01X82500Y339000D02*
X82750Y339250D01*
X96067D01*
X99817Y335500D01*
X136000D01*
X140500Y340000D01*
X145501D01*
X149501Y344000D01*
X162000D01*
X170500Y352500D01*
X189316D01*
X194316Y357500D01*
X230720D01*
X239220Y349000D01*
X275733D01*
X284233Y340500D01*
X313501D01*
X331351Y322650D01*
X337416D01*
X340024Y320042D01*
X348041D01*
X350583Y317500D01*
X387100D01*
X392500Y322900D01*
Y323900D01*
G01X83500Y360000D02*
X98500Y345000D01*
X102696D01*
X106196Y341500D01*
X130001D01*
X141001Y352500D01*
X153000D01*
X159000Y358500D01*
X186829D01*
X191829Y363500D01*
X235570D01*
X237780Y361290D01*
X240729D01*
X241229Y360790D01*
Y358720D01*
X241729Y358220D01*
X243229D01*
X243729Y358720D01*
Y360790D01*
X244229Y361290D01*
X245729D01*
X246229Y360790D01*
Y358720D01*
X246729Y358220D01*
X248229D01*
X248729Y358720D01*
Y360790D01*
X249229Y361290D01*
X250729D01*
X251229Y360790D01*
Y359000D01*
X251729Y358500D01*
X253229D01*
X253729Y359000D01*
Y360790D01*
X254229Y361290D01*
X255729D01*
X256229Y360790D01*
Y358720D01*
X256729Y358220D01*
X258229D01*
X258729Y358720D01*
Y360790D01*
X259229Y361290D01*
X260729D01*
X261229Y360790D01*
Y358720D01*
X261729Y358220D01*
X263229D01*
X263729Y358720D01*
Y360790D01*
X264229Y361290D01*
X265729D01*
X266229Y360790D01*
Y358720D01*
X266729Y358220D01*
X268229D01*
X268729Y358720D01*
Y360790D01*
X269229Y361290D01*
X271930D01*
X285220Y348000D01*
X355660D01*
X365660Y358000D01*
X387385D01*
X387885Y358500D01*
Y359430D01*
X388385Y359930D01*
X389885D01*
X390385Y359430D01*
Y358500D01*
X390885Y358000D01*
X393000D01*
X395000Y360000D01*
G01Y370000D02*
Y368999D01*
X393028Y367027D01*
Y366321D01*
X393980Y365368D01*
Y364662D01*
X392918Y363600D01*
X392212D01*
X391260Y364553D01*
X389994D01*
X386941Y361500D01*
X378367D01*
X377867Y362000D01*
Y370630D01*
X377367Y371130D01*
X375867D01*
X375367Y370630D01*
Y362000D01*
X374867Y361500D01*
X373367D01*
X372867Y362000D01*
Y366090D01*
X372367Y366590D01*
X370867D01*
X370367Y366090D01*
Y362000D01*
X369867Y361500D01*
X365361D01*
X353861Y350000D01*
X286049D01*
X270549Y365500D01*
X268287D01*
X267787Y365000D01*
Y363920D01*
X267287Y363420D01*
X265787D01*
X265287Y363920D01*
Y365000D01*
X264787Y365500D01*
X263287D01*
X262787Y365000D01*
Y363920D01*
X262287Y363420D01*
X260787D01*
X260287Y363920D01*
Y365000D01*
X259787Y365500D01*
X258287D01*
X257787Y365000D01*
Y363920D01*
X257287Y363420D01*
X255787D01*
X255287Y363920D01*
Y365000D01*
X254787Y365500D01*
X253287D01*
X252787Y365000D01*
Y363920D01*
X252287Y363420D01*
X250787D01*
X250287Y363920D01*
Y365000D01*
X249787Y365500D01*
X248287D01*
X247787Y365000D01*
Y363920D01*
X247287Y363420D01*
X245787D01*
X245287Y363920D01*
Y365000D01*
X244787Y365500D01*
X191000D01*
X186000Y360500D01*
X150501D01*
X146001Y356000D01*
X143500D01*
X141000Y358500D01*
X139000D01*
X138000Y357500D01*
X120500D01*
X116000Y362000D01*
X111500D01*
X108000Y358500D01*
X92500D01*
X91500Y359500D01*
G01X112500Y290000D02*
X113500D01*
X122300Y298800D01*
X138117D01*
X140067Y300750D01*
X153079D01*
X160500Y308171D01*
Y314501D01*
X177999Y332000D01*
X193217D01*
X194967Y330250D01*
X196833D01*
X198583Y332000D01*
X201171D01*
X201721Y332550D01*
X207591D01*
X209541Y334500D01*
X222328D01*
X224328Y336500D01*
X229000D01*
X232000Y333500D01*
X262512D01*
X290012Y306000D01*
X302500D01*
X306500Y310000D01*
X333316D01*
X335316Y308000D01*
X344500D01*
X346000Y306500D01*
G01X351000Y308000D02*
X348250Y310750D01*
X336238D01*
X334488Y312500D01*
X306001D01*
X301501Y308000D01*
X290841D01*
X263341Y335500D01*
X233000D01*
X230000Y338500D01*
X223499D01*
X221499Y336500D01*
X208712D01*
X206762Y334550D01*
X201450D01*
X200000Y336000D01*
X179000D01*
X158500Y315500D01*
Y309000D01*
X152250Y302750D01*
X139238D01*
X137288Y300800D01*
X121300D01*
X113500Y293000D01*
X105500D01*
X102500Y290000D01*
G01X420500Y366000D02*
X426000Y360500D01*
Y352500D01*
X425410Y351910D01*
X421010D01*
X416860Y356060D01*
X404200D01*
X402360Y354220D01*
Y352090D01*
X399270Y349000D01*
X381280D01*
X376280Y344000D01*
X358600D01*
X357500Y342900D01*
X342859D01*
X338959Y339000D01*
X332170D01*
X330420Y340750D01*
X320966D01*
X319216Y342500D01*
X285062D01*
X276382Y351180D01*
X240360D01*
X232040Y359500D01*
X193487D01*
X188487Y354500D01*
X169212D01*
X160712Y346000D01*
X147829D01*
X143829Y342000D01*
X139500D01*
X135000Y337500D01*
X101000D01*
X97500Y341000D01*
G01X101500D02*
X103000Y339500D01*
X132500D01*
X137000Y344000D01*
X143000D01*
X147000Y348000D01*
X159883D01*
X168383Y356500D01*
X187658D01*
X192658Y361500D01*
X233870D01*
X239450Y355920D01*
X262089D01*
X262589Y355420D01*
Y354160D01*
X263089Y353660D01*
X264589D01*
X265089Y354160D01*
Y355420D01*
X265589Y355920D01*
X267089D01*
X267589Y355420D01*
Y354160D01*
X268089Y353660D01*
X269589D01*
X270089Y354160D01*
Y355420D01*
X270589Y355920D01*
X274471D01*
X284391Y346000D01*
X327999D01*
X332999Y341000D01*
X337890D01*
X342390Y345500D01*
X356100D01*
X357900Y347300D01*
X361801D01*
X363274Y348773D01*
Y352144D01*
X367130Y356000D01*
X393829D01*
X393929Y356100D01*
X398180D01*
X403160Y361080D01*
X415920D01*
X422500Y354500D01*
G01X99500Y370000D02*
X101000Y371500D01*
X102500D01*
X108500Y377500D01*
X115500D01*
X117000Y376000D01*
X119000D01*
X127000Y368000D01*
X136500D01*
X140000Y364500D01*
X183999D01*
X188999Y369500D01*
X272207D01*
X287707Y354000D01*
X352000D01*
X376050Y378050D01*
X381033D01*
X381583Y377500D01*
X392000D01*
X403500Y366000D01*
X417317D01*
X419567Y368250D01*
X421750D01*
X428500Y361500D01*
Y346000D01*
G01X126000Y72000D02*
X128590D01*
X139770Y83180D01*
X181622D01*
X184000Y80802D01*
Y75000D01*
X194000Y65000D01*
X207001D01*
X210931Y61070D01*
X224931D01*
X227501Y58500D01*
X247001D01*
X253001Y64500D01*
X292440D01*
X292540Y64600D01*
X322310D01*
X322460Y64750D01*
X336067D01*
X339567Y61250D01*
X341433D01*
X343433Y63250D01*
X365297D01*
X372197Y56350D01*
X482837D01*
X514000Y87513D01*
Y92999D01*
X517000Y95999D01*
Y96171D01*
X519500Y98671D01*
Y121489D01*
X517000Y123989D01*
Y162159D01*
X500310Y178849D01*
Y186433D01*
X498583Y188160D01*
X481450D01*
X477610Y184320D01*
X473030D01*
X471084Y182374D01*
X469870D01*
G01X126067Y104043D02*
X143740Y86370D01*
X181261D01*
X186000Y81631D01*
Y77000D01*
X192700Y70300D01*
X205590D01*
X212820Y63070D01*
X225930D01*
X228500Y60500D01*
X245829D01*
X251829Y66500D01*
X290000D01*
X290600Y67100D01*
X322939D01*
X323289Y66750D01*
X364626D01*
X373026Y58350D01*
X482008D01*
X511500Y87842D01*
Y93500D01*
X517500Y99500D01*
Y120260D01*
X514500Y123260D01*
Y140817D01*
X512250Y143067D01*
Y164080D01*
X498250Y178080D01*
Y185310D01*
X498060Y185500D01*
G01X148500Y62500D02*
X150000Y64000D01*
X174990D01*
X179000Y68010D01*
X184500D01*
X192560Y59950D01*
X197449D01*
X210899Y46500D01*
X225500D01*
X227000Y45000D01*
X246000D01*
X249500Y48500D01*
X282900D01*
X288250Y53850D01*
X308150D01*
X313000Y58700D01*
X347200D01*
X349500Y61000D01*
G01X139500Y62500D02*
X142500Y59500D01*
X149500D01*
X151250Y61250D01*
X175250D01*
X180000Y66000D01*
X183500D01*
X192000Y57500D01*
X197070D01*
X210070Y44500D01*
X224500D01*
X226000Y43000D01*
X247000D01*
X250500Y46500D01*
X284500D01*
X289621Y51621D01*
X309620D01*
X314399Y56400D01*
X349980D01*
X354500Y60920D01*
G01X135000Y312000D02*
Y318500D01*
X137250Y320750D01*
Y333250D01*
X142000Y338000D01*
X146330D01*
X149880Y341550D01*
X167633D01*
X176583Y350500D01*
X195830D01*
X196880Y351550D01*
X205933D01*
X208883Y354500D01*
X223000D01*
X230000Y347500D01*
G01X225500D02*
X221500Y351500D01*
X210883D01*
X205933Y346550D01*
X201114D01*
X200614Y346050D01*
Y344500D01*
X200114Y344000D01*
X198614D01*
X198114Y344500D01*
Y346050D01*
X197614Y346550D01*
X196114D01*
X195614Y346050D01*
Y344500D01*
X195114Y344000D01*
X193614D01*
X193114Y344500D01*
Y346050D01*
X192614Y346550D01*
X191114D01*
X190614Y346050D01*
Y344500D01*
X190114Y344000D01*
X188614D01*
X188114Y344500D01*
Y346050D01*
X187614Y346550D01*
X186114D01*
X185614Y346050D01*
Y344500D01*
X185114Y344000D01*
X183614D01*
X183114Y344500D01*
Y346050D01*
X182614Y346550D01*
X177633D01*
X167633Y336550D01*
X159223D01*
X158723Y337050D01*
Y339000D01*
X158223Y339500D01*
X156723D01*
X156223Y339000D01*
Y337050D01*
X155723Y336550D01*
X154223D01*
X153723Y337050D01*
Y339000D01*
X153223Y339500D01*
X151723D01*
X151223Y339000D01*
Y337050D01*
X150723Y336550D01*
X148550D01*
X146000Y334000D01*
G01X138500Y387500D02*
X138000Y387000D01*
Y382000D01*
X135500Y379500D01*
Y371500D01*
X140750Y366250D01*
X183201D01*
X187951Y371000D01*
X276000D01*
X290000Y357000D01*
X350622D01*
X370000Y376378D01*
Y385000D01*
X379000Y394000D01*
X398541D01*
X405541Y387000D01*
X419000D01*
X425000Y381000D01*
G01X430000D02*
X429000D01*
X421500Y388500D01*
X406500D01*
X399500Y395500D01*
X375000D01*
X368500Y389000D01*
Y377000D01*
X350000Y358500D01*
X291000D01*
X277000Y372500D01*
X187329D01*
X182579Y367750D01*
X147067D01*
X145317Y369500D01*
X141000D01*
X138250Y372250D01*
G01X307300Y61300D02*
X252751D01*
X247451Y56000D01*
X214939D01*
X213690Y57249D01*
X210201D01*
X204950Y62500D01*
X192839D01*
X180620Y74719D01*
Y77890D01*
G01X312500Y307500D02*
X308500Y303500D01*
X289500D01*
X264000Y329000D01*
X228000D01*
X224500Y332500D01*
X215000D01*
X210400Y327900D01*
X201700D01*
G01X207880Y78740D02*
X209130Y79990D01*
X210430D01*
X214290Y76130D01*
X221811D01*
X227521Y81840D01*
X229561D01*
X232708Y78693D01*
X305600D01*
X309193Y75100D01*
X323426D01*
X325776Y72750D01*
X367113D01*
X375513Y64350D01*
X415177D01*
X416987Y66160D01*
X455561D01*
X457000Y67599D01*
Y68896D01*
X457500Y69396D01*
X475300D01*
X475800Y69896D01*
Y71396D01*
X475300Y71896D01*
X457500D01*
X457000Y72396D01*
Y77700D01*
X460300Y81000D01*
X464829D01*
X470829Y87000D01*
X484158D01*
X486255Y89097D01*
X486963D01*
X489026Y87034D01*
X489734D01*
X490794Y88094D01*
Y88802D01*
X488731Y90865D01*
Y91573D01*
X489791Y92633D01*
X490499D01*
X492562Y90570D01*
X493270D01*
X494330Y91630D01*
Y92338D01*
X492267Y94401D01*
Y95109D01*
X493327Y96169D01*
X494035D01*
X496098Y94106D01*
X496806D01*
X497866Y95166D01*
Y95874D01*
X495803Y97937D01*
Y98645D01*
X502658Y105500D01*
X508000D01*
G01X203000Y75000D02*
Y84921D01*
X204579Y86500D01*
X237000D01*
X240807Y82693D01*
X308507D01*
X311800Y79400D01*
X324784D01*
X327434Y76750D01*
X368771D01*
X377171Y68350D01*
X413519D01*
X415669Y70500D01*
X446329D01*
X453000Y77171D01*
Y84183D01*
X458067Y89250D01*
X466750D01*
X475000Y97500D01*
X489000D01*
X507000Y115500D01*
X508000D01*
G01X465933Y178437D02*
X467583Y180087D01*
X476000D01*
X476627Y180714D01*
X480178D01*
X481126Y179766D01*
X486734D01*
X490000Y176500D01*
Y174498D01*
X494498Y170000D01*
X499512D01*
X508250Y161262D01*
Y141409D01*
X510500Y139159D01*
Y120500D01*
X512500Y118500D01*
Y101000D01*
X506000Y94500D01*
Y88000D01*
X482160Y64160D01*
X417816D01*
X416006Y62350D01*
X374684D01*
X366284Y70750D01*
X324947D01*
X322948Y72749D01*
X308451D01*
X304700Y76500D01*
X292500D01*
X288500Y72500D01*
X264500D01*
X262500Y74500D01*
X254171D01*
X244171Y64500D01*
X230828D01*
X223988Y71340D01*
X215651D01*
X210551Y76440D01*
X207139D01*
X205730Y77849D01*
Y80940D01*
X207800Y83010D01*
G01X508000Y110500D02*
X504829D01*
X489579Y95250D01*
X476250D01*
X464000Y83000D01*
X459100D01*
X455000Y78900D01*
Y76000D01*
X451792Y72792D01*
Y72084D01*
X453834Y70042D01*
Y69334D01*
X452774Y68274D01*
X452066D01*
X450024Y70316D01*
X449316D01*
X447160Y68160D01*
X416158D01*
X414348Y66350D01*
X376342D01*
X367942Y74750D01*
X326605D01*
X323955Y77400D01*
X310293D01*
X307000Y80693D01*
X239807D01*
X236650Y83850D01*
X216540D01*
X214810Y82120D01*
Y78810D01*
G01X263300Y52200D02*
X260800D01*
X260100Y51500D01*
X243000D01*
X240418Y48918D01*
X229582D01*
G01X253967Y93443D02*
X254257D01*
X263007Y84693D01*
X292193D01*
X302230Y94730D01*
X314183D01*
X330163Y78750D01*
X348750D01*
X352500Y82500D01*
X354000D01*
G01X265967Y93443D02*
X272717Y86693D01*
X290693D01*
X300960Y96960D01*
X314782D01*
X330992Y80750D01*
X347250D01*
X349000Y82500D01*
G01X277867Y93443D02*
X292443D01*
X299000Y100000D01*
X314571D01*
X331821Y82750D01*
X344433D01*
X346683Y85000D01*
X355500D01*
X361500Y79000D01*
X369350D01*
X378000Y70350D01*
X412690D01*
X414840Y72500D01*
X418500D01*
X421200Y75200D01*
X425800D01*
X428010Y72990D01*
X445990D01*
X451000Y78000D01*
Y86500D01*
X459000Y94500D01*
X469000D01*
X474050Y99550D01*
X487258D01*
X497000Y109292D01*
Y116359D01*
X499550Y118909D01*
Y127443D01*
X501120Y129013D01*
Y142708D01*
X500520Y143308D01*
Y150480D01*
X497000Y154000D01*
G01X336500Y295000D02*
Y291000D01*
X332500Y287000D01*
X320500D01*
X309000Y275500D01*
Y264329D01*
X304717Y260046D01*
Y201282D01*
X306750Y199249D01*
Y174421D01*
X310000Y171171D01*
Y168683D01*
X306500Y165183D01*
Y161500D01*
X307500Y160500D01*
G01X344500Y265000D02*
Y288000D01*
X346500Y290000D01*
Y296000D01*
X344000Y298500D01*
X335500D01*
X333500Y296500D01*
Y290500D01*
X331500Y288500D01*
X319000D01*
X303217Y272717D01*
Y199284D01*
X305250Y197251D01*
Y175921D01*
X303000Y173671D01*
Y164500D01*
X303500Y164000D01*
G01X312000Y264500D02*
X306717Y259217D01*
Y202111D01*
X308750Y200078D01*
Y175250D01*
X312500Y171500D01*
Y160500D01*
G01X334350Y282000D02*
Y281350D01*
X330583Y277583D01*
X329875D01*
X326334Y281124D01*
X325626D01*
X324566Y280064D01*
Y279356D01*
X328107Y275815D01*
Y275107D01*
X327047Y274047D01*
X326339D01*
X322798Y277588D01*
X322090D01*
X321030Y276528D01*
Y275820D01*
X324571Y272279D01*
Y271571D01*
X323511Y270511D01*
X322803D01*
X319262Y274052D01*
X318554D01*
X317494Y272992D01*
Y272284D01*
X321035Y268743D01*
Y268035D01*
X318750Y265750D01*
Y261031D01*
X319500Y260281D01*
Y225500D01*
X322000Y223000D01*
X326500D01*
X327923Y221577D01*
G01X335153Y217875D02*
X328028Y225000D01*
X322829D01*
X321500Y226329D01*
Y261110D01*
X320750Y261860D01*
Y264250D01*
X337000Y280500D01*
Y286000D01*
X344000Y293000D01*
Y295000D01*
G01X312500Y225400D02*
X309000Y228900D01*
Y257000D01*
X314500Y262500D01*
Y266500D01*
X312000Y269000D01*
G01Y256500D02*
X315500Y253000D01*
Y233700D01*
X311900Y230100D01*
Y229900D01*
G01X318000Y268500D02*
Y267830D01*
X316750Y266579D01*
Y260202D01*
X317500Y259452D01*
Y223500D01*
X323250Y217750D01*
X328250D01*
X330000Y216000D01*
Y211000D01*
X340118Y200882D01*
Y179382D01*
X342750Y176750D01*
X350550D01*
X352300Y175000D01*
G01X327500Y232000D02*
Y236000D01*
X325500Y238000D01*
Y252859D01*
X326450Y253809D01*
Y255591D01*
X323500Y258541D01*
Y263000D01*
G01X329433Y-125500D02*
Y-133000D01*
X333167D01*
G01X340480D02*
Y-128000D01*
G01Y-128875D02*
X340107Y-128375D01*
X339547Y-128125D01*
X338893Y-128000D01*
X338240Y-128250D01*
X337680Y-128750D01*
X337307Y-129500D01*
X337120Y-130500D01*
X337307Y-131500D01*
X337680Y-132250D01*
X338240Y-132750D01*
X338893Y-133000D01*
X339547Y-132875D01*
X340107Y-132500D01*
X340480Y-132000D01*
G01X344340Y-135250D02*
X344900Y-135500D01*
X345647Y-135250D01*
X346113Y-134750D01*
X346487Y-134125D01*
X347047Y-132125D01*
X348260Y-128000D01*
G01X345273D02*
X347047Y-132125D01*
G01X352400Y-129625D02*
X355387D01*
X355107Y-128750D01*
X354640Y-128250D01*
X353987Y-128000D01*
X353333Y-128125D01*
X352773Y-128500D01*
X352400Y-129375D01*
X352213Y-130125D01*
Y-130875D01*
X352400Y-131625D01*
X352867Y-132375D01*
X353427Y-132875D01*
X354080Y-133000D01*
X354733Y-132750D01*
X355387Y-132000D01*
G01X359993Y-133000D02*
Y-128000D01*
G01Y-129000D02*
X360460Y-128500D01*
X360927Y-128125D01*
X361580Y-128000D01*
X362047Y-128125D01*
X362607Y-128500D01*
G01X368800Y-133250D02*
X368613Y-133125D01*
Y-132875D01*
X368800Y-132750D01*
X368987Y-132875D01*
Y-133125D01*
X368800Y-133250D01*
G01Y-129875D02*
X368613Y-129750D01*
Y-129500D01*
X368800Y-129375D01*
X368987Y-129500D01*
Y-129750D01*
X368800Y-129875D01*
G01X336747Y-120500D02*
Y-113000D01*
X338613D01*
X339360Y-113375D01*
X339920Y-113875D01*
X340387Y-114625D01*
X340760Y-115500D01*
X340853Y-116750D01*
X340760Y-118000D01*
X340387Y-118875D01*
X339920Y-119625D01*
X339360Y-120125D01*
X338613Y-120500D01*
X336747D01*
G01X347980D02*
Y-115500D01*
G01Y-116375D02*
X347607Y-115875D01*
X347047Y-115625D01*
X346393Y-115500D01*
X345740Y-115750D01*
X345180Y-116250D01*
X344807Y-117000D01*
X344620Y-118000D01*
X344807Y-119000D01*
X345180Y-119750D01*
X345740Y-120250D01*
X346393Y-120500D01*
X347047Y-120375D01*
X347607Y-120000D01*
X347980Y-119500D01*
G01X353800Y-113000D02*
Y-120500D01*
G01X352493Y-115500D02*
X355107D01*
G01X359900Y-117125D02*
X362887D01*
X362607Y-116250D01*
X362140Y-115750D01*
X361487Y-115500D01*
X360833Y-115625D01*
X360273Y-116000D01*
X359900Y-116875D01*
X359713Y-117625D01*
Y-118375D01*
X359900Y-119125D01*
X360367Y-119875D01*
X360927Y-120375D01*
X361580Y-120500D01*
X362233Y-120250D01*
X362887Y-119500D01*
G01X368800Y-120750D02*
X368613Y-120625D01*
Y-120375D01*
X368800Y-120250D01*
X368987Y-120375D01*
Y-120625D01*
X368800Y-120750D01*
G01Y-117375D02*
X368613Y-117250D01*
Y-117000D01*
X368800Y-116875D01*
X368987Y-117000D01*
Y-117250D01*
X368800Y-117375D01*
G01X382027Y-114250D02*
X382587Y-113500D01*
X383240Y-113125D01*
X383987Y-113000D01*
X384920Y-113250D01*
X385573Y-113875D01*
X385760Y-114625D01*
X385667Y-115375D01*
X385293Y-116000D01*
X383427Y-117250D01*
X382587Y-118125D01*
X382027Y-119375D01*
X381840Y-120500D01*
X385760D01*
G01X391300Y-113000D02*
X390553Y-113250D01*
X389993Y-113875D01*
X389620Y-114625D01*
X389340Y-115625D01*
X389247Y-116750D01*
X389340Y-117875D01*
X389620Y-118875D01*
X389993Y-119625D01*
X390553Y-120250D01*
X391300Y-120500D01*
X392047Y-120250D01*
X392607Y-119625D01*
X392980Y-118875D01*
X393260Y-117875D01*
X393353Y-116750D01*
X393260Y-115625D01*
X392980Y-114625D01*
X392607Y-113875D01*
X392047Y-113250D01*
X391300Y-113000D01*
G01X397027Y-114250D02*
X397587Y-113500D01*
X398240Y-113125D01*
X398987Y-113000D01*
X399920Y-113250D01*
X400573Y-113875D01*
X400760Y-114625D01*
X400667Y-115375D01*
X400293Y-116000D01*
X398427Y-117250D01*
X397587Y-118125D01*
X397027Y-119375D01*
X396840Y-120500D01*
X400760D01*
G01X404527Y-114250D02*
X405087Y-113500D01*
X405740Y-113125D01*
X406487Y-113000D01*
X407420Y-113250D01*
X408073Y-113875D01*
X408260Y-114625D01*
X408167Y-115375D01*
X407793Y-116000D01*
X405927Y-117250D01*
X405087Y-118125D01*
X404527Y-119375D01*
X404340Y-120500D01*
X408260D01*
G01X412587Y-118000D02*
X415013D01*
G01X421300Y-113000D02*
X420553Y-113250D01*
X419993Y-113875D01*
X419620Y-114625D01*
X419340Y-115625D01*
X419247Y-116750D01*
X419340Y-117875D01*
X419620Y-118875D01*
X419993Y-119625D01*
X420553Y-120250D01*
X421300Y-120500D01*
X422047Y-120250D01*
X422607Y-119625D01*
X422980Y-118875D01*
X423260Y-117875D01*
X423353Y-116750D01*
X423260Y-115625D01*
X422980Y-114625D01*
X422607Y-113875D01*
X422047Y-113250D01*
X421300Y-113000D01*
G01X427027Y-114250D02*
X427587Y-113500D01*
X428240Y-113125D01*
X428987Y-113000D01*
X429920Y-113250D01*
X430573Y-113875D01*
X430760Y-114625D01*
X430667Y-115375D01*
X430293Y-116000D01*
X428427Y-117250D01*
X427587Y-118125D01*
X427027Y-119375D01*
X426840Y-120500D01*
X430760D01*
G01X435087Y-118000D02*
X437513D01*
G01X442027Y-114250D02*
X442587Y-113500D01*
X443240Y-113125D01*
X443987Y-113000D01*
X444920Y-113250D01*
X445573Y-113875D01*
X445760Y-114625D01*
X445667Y-115375D01*
X445293Y-116000D01*
X443427Y-117250D01*
X442587Y-118125D01*
X442027Y-119375D01*
X441840Y-120500D01*
X445760D01*
G01X449247Y-119375D02*
X449807Y-120000D01*
X450460Y-120375D01*
X451300Y-120500D01*
X452140Y-120250D01*
X452793Y-119750D01*
X453260Y-118875D01*
X453353Y-117875D01*
X453167Y-116875D01*
X452700Y-116250D01*
X452047Y-115750D01*
X451393Y-115625D01*
X450740Y-115750D01*
X449900Y-116250D01*
X450180Y-113000D01*
X452700D01*
G01X336933Y-108000D02*
Y-100500D01*
X339267D01*
X340013Y-100875D01*
X340480Y-101375D01*
X340667Y-102375D01*
X340480Y-103375D01*
X339920Y-104000D01*
X339267Y-104375D01*
X336933D01*
G01X339267D02*
X340667Y-108000D01*
G01X344900Y-104625D02*
X347887D01*
X347607Y-103750D01*
X347140Y-103250D01*
X346487Y-103000D01*
X345833Y-103125D01*
X345273Y-103500D01*
X344900Y-104375D01*
X344713Y-105125D01*
Y-105875D01*
X344900Y-106625D01*
X345367Y-107375D01*
X345927Y-107875D01*
X346580Y-108000D01*
X347233Y-107750D01*
X347887Y-107000D01*
G01X352120Y-103000D02*
X353800Y-108000D01*
X355480Y-103000D01*
G01X368800Y-108250D02*
X368613Y-108125D01*
Y-107875D01*
X368800Y-107750D01*
X368987Y-107875D01*
Y-108125D01*
X368800Y-108250D01*
G01Y-104875D02*
X368613Y-104750D01*
Y-104500D01*
X368800Y-104375D01*
X368987Y-104500D01*
Y-104750D01*
X368800Y-104875D01*
G01X383800Y-100500D02*
X383053Y-100750D01*
X382493Y-101375D01*
X382120Y-102125D01*
X381840Y-103125D01*
X381747Y-104250D01*
X381840Y-105375D01*
X382120Y-106375D01*
X382493Y-107125D01*
X383053Y-107750D01*
X383800Y-108000D01*
X384547Y-107750D01*
X385107Y-107125D01*
X385480Y-106375D01*
X385760Y-105375D01*
X385853Y-104250D01*
X385760Y-103125D01*
X385480Y-102125D01*
X385107Y-101375D01*
X384547Y-100750D01*
X383800Y-100500D01*
G01X391300Y-108000D02*
Y-100500D01*
X390180Y-102000D01*
G01Y-108000D02*
X392420D01*
G01X336933Y-95500D02*
Y-88000D01*
X339173D01*
X339920Y-88375D01*
X340480Y-89250D01*
X340667Y-90250D01*
X340480Y-91250D01*
X340013Y-92000D01*
X339173Y-92375D01*
X336933D01*
G01X344620Y-95750D02*
X347980Y-88000D01*
G01X351653Y-95500D02*
Y-88000D01*
X355947Y-95500D01*
Y-88000D01*
G01X368800Y-95750D02*
X368613Y-95625D01*
Y-95375D01*
X368800Y-95250D01*
X368987Y-95375D01*
Y-95625D01*
X368800Y-95750D01*
G01Y-92375D02*
X368613Y-92250D01*
Y-92000D01*
X368800Y-91875D01*
X368987Y-92000D01*
Y-92250D01*
X368800Y-92375D01*
G01X381933Y-95500D02*
Y-88000D01*
X384267D01*
X385013Y-88375D01*
X385480Y-88875D01*
X385667Y-89875D01*
X385480Y-90875D01*
X384920Y-91500D01*
X384267Y-91875D01*
X381933D01*
G01X384267D02*
X385667Y-95500D01*
G01X392420D02*
Y-88000D01*
X388967Y-93375D01*
X393633D01*
G01X398800Y-88000D02*
X398053Y-88250D01*
X397493Y-88875D01*
X397120Y-89625D01*
X396840Y-90625D01*
X396747Y-91750D01*
X396840Y-92875D01*
X397120Y-93875D01*
X397493Y-94625D01*
X398053Y-95250D01*
X398800Y-95500D01*
X399547Y-95250D01*
X400107Y-94625D01*
X400480Y-93875D01*
X400760Y-92875D01*
X400853Y-91750D01*
X400760Y-90625D01*
X400480Y-89625D01*
X400107Y-88875D01*
X399547Y-88250D01*
X398800Y-88000D01*
G01X406300D02*
X405553Y-88250D01*
X404993Y-88875D01*
X404620Y-89625D01*
X404340Y-90625D01*
X404247Y-91750D01*
X404340Y-92875D01*
X404620Y-93875D01*
X404993Y-94625D01*
X405553Y-95250D01*
X406300Y-95500D01*
X407047Y-95250D01*
X407607Y-94625D01*
X407980Y-93875D01*
X408260Y-92875D01*
X408353Y-91750D01*
X408260Y-90625D01*
X407980Y-89625D01*
X407607Y-88875D01*
X407047Y-88250D01*
X406300Y-88000D01*
G01X412027Y-92375D02*
X412680Y-91500D01*
X413240Y-91000D01*
X413987Y-90750D01*
X414640Y-91000D01*
X415107Y-91500D01*
X415480Y-92250D01*
X415573Y-93125D01*
X415480Y-93875D01*
X415107Y-94625D01*
X414547Y-95250D01*
X413893Y-95500D01*
X413147Y-95250D01*
X412493Y-94500D01*
X412120Y-93375D01*
X412027Y-92125D01*
X412213Y-90500D01*
X412493Y-89625D01*
X412960Y-88750D01*
X413613Y-88125D01*
X414267Y-88000D01*
X414920Y-88250D01*
X415387Y-88875D01*
G01X420087Y-93000D02*
X422513D01*
G01X429547Y-91500D02*
X429920Y-91125D01*
X430200Y-90500D01*
X430387Y-89625D01*
X430200Y-88875D01*
X429827Y-88375D01*
X429173Y-88000D01*
X426653D01*
Y-95500D01*
X429733D01*
X430387Y-95000D01*
X430760Y-94250D01*
X430947Y-93375D01*
X430760Y-92500D01*
X430200Y-91750D01*
X429547Y-91500D01*
X426653D01*
G01X436300Y-88000D02*
X435553Y-88250D01*
X434993Y-88875D01*
X434620Y-89625D01*
X434340Y-90625D01*
X434247Y-91750D01*
X434340Y-92875D01*
X434620Y-93875D01*
X434993Y-94625D01*
X435553Y-95250D01*
X436300Y-95500D01*
X437047Y-95250D01*
X437607Y-94625D01*
X437980Y-93875D01*
X438260Y-92875D01*
X438353Y-91750D01*
X438260Y-90625D01*
X437980Y-89625D01*
X437607Y-88875D01*
X437047Y-88250D01*
X436300Y-88000D01*
G01X443800D02*
X443053Y-88250D01*
X442493Y-88875D01*
X442120Y-89625D01*
X441840Y-90625D01*
X441747Y-91750D01*
X441840Y-92875D01*
X442120Y-93875D01*
X442493Y-94625D01*
X443053Y-95250D01*
X443800Y-95500D01*
X444547Y-95250D01*
X445107Y-94625D01*
X445480Y-93875D01*
X445760Y-92875D01*
X445853Y-91750D01*
X445760Y-90625D01*
X445480Y-89625D01*
X445107Y-88875D01*
X444547Y-88250D01*
X443800Y-88000D01*
G01X451300D02*
X450553Y-88250D01*
X449993Y-88875D01*
X449620Y-89625D01*
X449340Y-90625D01*
X449247Y-91750D01*
X449340Y-92875D01*
X449620Y-93875D01*
X449993Y-94625D01*
X450553Y-95250D01*
X451300Y-95500D01*
X452047Y-95250D01*
X452607Y-94625D01*
X452980Y-93875D01*
X453260Y-92875D01*
X453353Y-91750D01*
X453260Y-90625D01*
X452980Y-89625D01*
X452607Y-88875D01*
X452047Y-88250D01*
X451300Y-88000D01*
G01X458800Y-95500D02*
Y-88000D01*
X457680Y-89500D01*
G01Y-95500D02*
X459920D01*
G01X465087Y-93000D02*
X467513D01*
G01X473800Y-88000D02*
X473053Y-88250D01*
X472493Y-88875D01*
X472120Y-89625D01*
X471840Y-90625D01*
X471747Y-91750D01*
X471840Y-92875D01*
X472120Y-93875D01*
X472493Y-94625D01*
X473053Y-95250D01*
X473800Y-95500D01*
X474547Y-95250D01*
X475107Y-94625D01*
X475480Y-93875D01*
X475760Y-92875D01*
X475853Y-91750D01*
X475760Y-90625D01*
X475480Y-89625D01*
X475107Y-88875D01*
X474547Y-88250D01*
X473800Y-88000D01*
G01X479527Y-89250D02*
X480087Y-88500D01*
X480740Y-88125D01*
X481487Y-88000D01*
X482420Y-88250D01*
X483073Y-88875D01*
X483260Y-89625D01*
X483167Y-90375D01*
X482793Y-91000D01*
X480927Y-92250D01*
X480087Y-93125D01*
X479527Y-94375D01*
X479340Y-95500D01*
X483260D01*
G01X324000Y227500D02*
X327500D01*
X331000Y231000D01*
Y242500D01*
X330000Y243500D01*
Y255500D01*
X331000Y256500D01*
Y260500D01*
X330500Y261000D01*
Y265000D01*
G01X337500D02*
X336000Y263500D01*
Y251000D01*
X332600Y247600D01*
Y246600D01*
G01X346500Y174000D02*
X345500Y173000D01*
Y152000D01*
X353000Y144500D01*
X357000D01*
X362000Y139500D01*
X372000D01*
X379000Y132500D01*
Y123500D01*
X363500Y108000D01*
Y105500D01*
X359500Y101500D01*
X346500D01*
X345000Y103000D01*
X344000D01*
G01X458059Y190248D02*
X456311Y188500D01*
X433501D01*
X432000Y186999D01*
Y181273D01*
X429500Y178773D01*
Y159496D01*
X427004Y157000D01*
X414744D01*
X412366Y154622D01*
Y150166D01*
X411353Y149153D01*
X406897D01*
X405329Y147585D01*
Y147136D01*
X402748Y144555D01*
X402299D01*
X400555Y142811D01*
Y142362D01*
X398810Y140617D01*
X386382D01*
X384100Y142899D01*
Y161000D01*
X366250Y178850D01*
X356150D01*
X353500Y181500D01*
X344500D01*
G01X530000Y406500D02*
X523000D01*
X506000Y389500D01*
X483000D01*
X443500Y350000D01*
X439000D01*
X424965Y335965D01*
Y326612D01*
X416543Y318190D01*
Y300457D01*
X414086Y298000D01*
X406500D01*
X402050Y293550D01*
Y276171D01*
X399879Y274000D01*
X384990D01*
X377490Y266500D01*
X374500D01*
X371250Y269750D01*
X368567D01*
X367250Y268433D01*
Y266249D01*
X361250Y260249D01*
Y260153D01*
X359347Y258250D01*
X359251D01*
X354151Y253150D01*
X352798D01*
X344650Y245002D01*
Y221649D01*
X343780Y220779D01*
Y216109D01*
X346500Y213389D01*
Y204500D01*
X342700Y200700D01*
Y186499D01*
X344821Y184378D01*
X357037D01*
X357509Y184850D01*
X363150D01*
X378150Y169850D01*
X381850D01*
X384250Y172250D01*
X393750D01*
X395500Y174000D01*
X407380D01*
X410816Y170564D01*
G01X578937Y417500D02*
X572567D01*
X570067Y415000D01*
X566000D01*
X559000Y422000D01*
X542500D01*
X536000Y415500D01*
Y403500D01*
X535000Y402500D01*
Y376744D01*
X519756Y361500D01*
X509500D01*
X503250Y367750D01*
X473913D01*
X471892Y365729D01*
X466851D01*
X453500Y352378D01*
Y347337D01*
X445500Y339337D01*
Y331500D01*
X437000Y323000D01*
X431000D01*
X423226Y315226D01*
Y300774D01*
X417150Y294698D01*
Y294650D01*
X411500Y289000D01*
X408500D01*
X406550Y287050D01*
Y274305D01*
X406500Y274255D01*
Y274000D01*
X402000Y269500D01*
X387552D01*
X379612Y261560D01*
X371818D01*
X363879Y253621D01*
Y248379D01*
X363000Y247500D01*
Y230000D01*
X362000Y229000D01*
X353500D01*
X352000Y227500D01*
Y211000D01*
X358600Y204400D01*
X366148D01*
X388174Y182374D01*
X391130D01*
G01X395067D02*
X393875D01*
X391961Y180460D01*
X387966D01*
X367049Y201377D01*
X358245D01*
X350000Y209622D01*
Y219122D01*
X347650Y221472D01*
Y243758D01*
X354042Y250150D01*
X358150D01*
X371060Y263060D01*
X378990D01*
X386930Y271000D01*
X401123D01*
X405050Y274927D01*
Y291050D01*
X408500Y294500D01*
X414830D01*
X421165Y300835D01*
Y316165D01*
X430000Y325000D01*
Y335041D01*
X440209Y345250D01*
X449291D01*
X452000Y347959D01*
Y353000D01*
X466229Y367229D01*
X471270D01*
X489041Y385000D01*
X520500D01*
X521000Y385500D01*
Y393783D01*
X529467Y402250D01*
X531762D01*
X534350Y404838D01*
Y417350D01*
X540500Y423500D01*
X561126D01*
X567126Y417500D01*
G01X614370D02*
Y413870D01*
X612000Y411500D01*
X597835D01*
X596335Y410000D01*
X562000D01*
X559500Y412500D01*
Y416500D01*
X555500Y420500D01*
X545500D01*
X541750Y416750D01*
Y406250D01*
X536500Y401000D01*
Y376122D01*
X520378Y360000D01*
X508000D01*
X502000Y366000D01*
X481390D01*
X476390Y361000D01*
X464244D01*
X455000Y351756D01*
Y346715D01*
X447500Y339215D01*
Y330500D01*
X436000Y319000D01*
X430500D01*
X425000Y313500D01*
Y300426D01*
X418650Y294076D01*
Y294028D01*
X411550Y286928D01*
Y276550D01*
X403000Y268000D01*
X388174D01*
X380234Y260060D01*
X372440D01*
X368000Y255620D01*
Y243500D01*
X370000Y241500D01*
Y230000D01*
X367500Y227500D01*
X360000D01*
X357750Y225250D01*
Y210872D01*
X362722Y205900D01*
X366770D01*
X386359Y186311D01*
X387193D01*
G01X602559Y417500D02*
X596499D01*
X588999Y425000D01*
X538500D01*
X532750Y419250D01*
Y405360D01*
X531140Y403750D01*
X522750D01*
X507000Y388000D01*
X483622D01*
X443622Y348000D01*
X440000D01*
X427500Y335500D01*
Y326000D01*
X418854Y317354D01*
Y300646D01*
X414604Y296396D01*
X407396D01*
X403550Y292550D01*
Y275549D01*
X400501Y272500D01*
X386090D01*
X378150Y264560D01*
X370438D01*
X357528Y251650D01*
X353420D01*
X346150Y244380D01*
Y220850D01*
X348500Y218500D01*
Y209000D01*
X358500Y199000D01*
X367303D01*
X383128Y183175D01*
Y178372D01*
G01X341500Y333500D02*
X344850Y330150D01*
X348610D01*
X349110Y330650D01*
Y338200D01*
X349610Y338700D01*
X351110D01*
X351610Y338200D01*
Y330650D01*
X352110Y330150D01*
X381609D01*
X382809Y331350D01*
X394650D01*
X408500Y317500D01*
Y316500D01*
G01X406879Y158753D02*
X408429Y160303D01*
X410803D01*
X413000Y162500D01*
Y173000D01*
X410500Y175500D01*
X394500D01*
X392500Y173500D01*
X378000D01*
X374600Y176900D01*
Y178200D01*
G01X373649Y185735D02*
X377500Y181884D01*
Y176000D01*
X378500Y175000D01*
X391000D01*
X393500Y177500D01*
Y179500D01*
X394500Y180500D01*
X407500D01*
X409000Y182000D01*
Y188432D01*
X410816Y190248D01*
G01X399005Y186311D02*
X397086Y188230D01*
X392270D01*
X389353Y191147D01*
X383646D01*
X367193Y207600D01*
X364000D01*
X363900Y207700D01*
X363178D01*
X359250Y211628D01*
Y223122D01*
X362128Y226000D01*
X369683D01*
X375000Y231317D01*
Y239878D01*
X369500Y245378D01*
Y254000D01*
X374000Y258500D01*
X381940D01*
X386440Y263000D01*
X401000D01*
X413500Y275500D01*
Y286756D01*
X420150Y293406D01*
Y293454D01*
X429348Y302652D01*
Y304848D01*
X438000Y313500D01*
Y318000D01*
X448000Y328000D01*
X452000D01*
X454000Y330000D01*
Y343593D01*
X456500Y346093D01*
Y351134D01*
X464866Y359500D01*
X477012D01*
X481512Y364000D01*
X501000D01*
X506500Y358500D01*
X521000D01*
X538350Y375850D01*
Y399850D01*
X543500Y405000D01*
Y416000D01*
X546500Y419000D01*
X553815D01*
X555315Y417500D01*
G01X548829Y416329D02*
X546000Y413500D01*
Y380500D01*
X522500Y357000D01*
X505500D01*
X500500Y362000D01*
X481634D01*
X477634Y358000D01*
X473500D01*
X456000Y340500D01*
Y329878D01*
X450000Y323878D01*
Y319500D01*
X449500Y319000D01*
X443122D01*
X440500Y316378D01*
Y308817D01*
X436076Y304393D01*
X433211D01*
X421650Y292832D01*
Y292784D01*
X415000Y286134D01*
Y273783D01*
X400050Y258833D01*
Y257500D01*
X399550Y257000D01*
X380999D01*
X376999Y253000D01*
X376783D01*
X376733Y252950D01*
X375451D01*
X371250Y248749D01*
Y245750D01*
X377000Y240000D01*
Y229500D01*
X372000Y224500D01*
X362750D01*
X360750Y222500D01*
Y212250D01*
X363800Y209200D01*
X367715D01*
X384457Y192458D01*
X396795D01*
X399005Y190248D01*
G01X434500Y302000D02*
X427150Y294650D01*
Y291967D01*
X425833Y290650D01*
X423650D01*
X418000Y285000D01*
Y269500D01*
X403500Y255000D01*
X381828D01*
X375850Y249022D01*
Y244650D01*
X382000Y238500D01*
Y235390D01*
X380250Y233640D01*
Y229750D01*
X393914Y216086D01*
X399914D01*
X401000Y215000D01*
Y197073D01*
X402073Y196000D01*
X411500D01*
X413000Y194500D01*
Y184558D01*
X410816Y182374D01*
G01X439000Y302000D02*
X429150Y292150D01*
Y291138D01*
X426662Y288650D01*
X424651D01*
X420500Y284499D01*
Y269000D01*
X404500Y253000D01*
X383117D01*
X377850Y247733D01*
Y245651D01*
X387250Y236251D01*
Y231360D01*
X390500Y228110D01*
Y222500D01*
X395500Y217500D01*
X400500D01*
X405000Y213000D01*
Y205500D01*
X406500Y204000D01*
X416000D01*
X417000Y203000D01*
Y184621D01*
X414753Y182374D01*
G01Y209933D02*
X411400Y213286D01*
Y225100D01*
X394000Y242500D01*
X390300D01*
X386000Y246800D01*
G01X380100D02*
X387309Y239591D01*
X387591D01*
X409200Y217982D01*
Y211549D01*
X410816Y209933D01*
G01X392500Y329100D02*
X393500D01*
X404750Y317850D01*
Y303250D01*
X407500Y300500D01*
G01X413000D02*
X414040Y301540D01*
Y320580D01*
X422590Y329130D01*
Y336590D01*
X431000Y345000D01*
Y351000D01*
X430500Y351500D01*
Y362329D01*
X422579Y370250D01*
X418738D01*
X417488Y369000D01*
X404110D01*
X392110Y381000D01*
X379500D01*
G01X411840Y353620D02*
X416303Y349157D01*
Y348449D01*
X414346Y346492D01*
Y345784D01*
X415406Y344724D01*
X416114D01*
X418071Y346681D01*
X418779D01*
X420420Y345040D01*
Y331860D01*
X410900Y322340D01*
Y313400D01*
X408500Y311000D01*
G01X418500Y117000D02*
Y124000D01*
X421000Y126500D01*
X428000D01*
X432000Y130500D01*
Y144505D01*
X434437Y146942D01*
G01Y150879D02*
X434379D01*
X430000Y146500D01*
Y130500D01*
X427500Y128000D01*
X419500D01*
X415000Y123500D01*
G01X436500Y237500D02*
X430150Y231150D01*
Y182023D01*
X426564Y178437D01*
G01X583000Y297000D02*
X568500Y311500D01*
X523329D01*
X509000Y325829D01*
Y332817D01*
X502250Y339567D01*
Y346751D01*
X493001Y356000D01*
X474499D01*
X458000Y339501D01*
Y329049D01*
X452500Y323549D01*
Y318000D01*
X451250Y316750D01*
X446749D01*
X443000Y313001D01*
Y304500D01*
X441250Y302750D01*
Y301067D01*
X435300Y295117D01*
Y290467D01*
X431000Y286167D01*
Y280999D01*
X423500Y273499D01*
Y267849D01*
X411900Y256249D01*
Y228734D01*
X416403Y224231D01*
Y207646D01*
X414753Y205996D01*
G01X434437Y213870D02*
X432200Y216107D01*
Y225200D01*
X439000Y232000D01*
Y239500D01*
X437500Y241000D01*
X426700D01*
X420900Y246800D01*
G01X438374Y135130D02*
Y133626D01*
X440500Y131500D01*
Y129365D01*
X445448Y124417D01*
X463083D01*
X466500Y121000D01*
Y110400D01*
G01X436500Y130000D02*
X430000Y123500D01*
X429000D01*
G01X471200Y115700D02*
Y119778D01*
X465061Y125917D01*
X448389D01*
X440500Y133806D01*
Y149068D01*
X442311Y150879D01*
G01X443811Y132420D02*
X448931Y127300D01*
X465800D01*
X482800Y110300D01*
G01X476800Y120700D02*
X468900Y128600D01*
X457580D01*
G01X497000Y341000D02*
X487000D01*
X483500Y337500D01*
X472500D01*
X466000Y331000D01*
Y319000D01*
X459000Y312000D01*
Y304500D01*
X451500Y297000D01*
Y272499D01*
X450750Y271749D01*
Y245067D01*
X454000Y241817D01*
Y224501D01*
X444470Y214971D01*
Y209460D01*
X443010Y208000D01*
X441820D01*
X440500Y206680D01*
Y192374D01*
X438374Y190248D01*
G01X448500Y237500D02*
X446000Y235000D01*
Y222500D01*
X440500Y217000D01*
Y212560D01*
G01X442311Y209933D02*
Y215811D01*
X451500Y225000D01*
Y240000D01*
X446250Y245250D01*
Y252336D01*
X445750Y252836D01*
X437400D01*
X436900Y253336D01*
Y254836D01*
X437400Y255336D01*
X445750D01*
X446250Y255836D01*
Y257336D01*
X445750Y257836D01*
X438500D01*
X437800Y258536D01*
Y259636D01*
X438500Y260336D01*
X445750D01*
X446250Y260836D01*
Y270750D01*
X449500Y274000D01*
Y301817D01*
X453250Y305567D01*
Y307249D01*
X457000Y310999D01*
Y312829D01*
X464000Y319829D01*
Y331829D01*
X473171Y341000D01*
X481000D01*
G01X434437Y202059D02*
X436410Y204032D01*
Y220389D01*
X441000Y224979D01*
Y240500D01*
X438000Y243500D01*
X432500D01*
X430500Y245500D01*
Y264150D01*
X443350Y277000D01*
Y296309D01*
X445500Y298459D01*
Y312500D01*
X447500Y314500D01*
X452000D01*
X456500Y319000D01*
X460342D01*
X461750Y320408D01*
Y334567D01*
X473250Y346067D01*
Y347933D01*
X476817Y351500D01*
X493000D01*
X500000Y344500D01*
Y338988D01*
X506500Y332488D01*
Y325500D01*
X528500Y303500D01*
Y299000D01*
G01X460000Y76000D02*
X460500D01*
X461500Y75000D01*
X482499D01*
X510500Y103001D01*
Y117499D01*
X508500Y119499D01*
Y138330D01*
X506250Y140580D01*
Y160433D01*
X501433Y165250D01*
X495067D01*
X493000Y167317D01*
Y168669D01*
X488000Y173669D01*
Y175501D01*
X486317Y177184D01*
X482314D01*
X481344Y176214D01*
X464219D01*
X461996Y178437D01*
G01X490970Y133500D02*
X487568D01*
X476170Y144900D01*
X465400D01*
X464000Y146300D01*
Y151500D01*
X462653Y152847D01*
X457009D01*
X456000Y153856D01*
Y156500D01*
X454122Y158378D01*
Y158753D01*
G01Y162690D02*
X454310D01*
X456000Y161000D01*
Y158000D01*
X457000Y157000D01*
X462650D01*
X464000Y155650D01*
Y154000D01*
X465000Y153000D01*
X474020D01*
X475540Y151480D01*
Y148710D01*
X485750Y138500D01*
X490970D01*
G01X461500Y311000D02*
X464500Y308000D01*
Y302000D01*
X460500Y298000D01*
X457000D01*
X454500Y295500D01*
Y256183D01*
X459750Y250933D01*
Y239750D01*
X464000Y235500D01*
Y228000D01*
X471500Y220500D01*
X474500D01*
X476500Y218500D01*
Y203500D01*
X471750Y198750D01*
Y192128D01*
X469870Y190248D01*
G01X586500Y107000D02*
X589000Y109500D01*
Y129500D01*
X581500Y137000D01*
X558000D01*
X553000Y142000D01*
X532500D01*
X526500Y148000D01*
Y163975D01*
X512000Y178475D01*
Y193829D01*
X503829Y202000D01*
X491500D01*
X490000Y203500D01*
Y208499D01*
X482250Y216249D01*
Y226578D01*
X479328Y229500D01*
X476000D01*
X468500Y237000D01*
Y256500D01*
X460500Y264500D01*
X458000D01*
X457000Y263500D01*
Y258500D01*
G01X586500Y112500D02*
Y119820D01*
X586000Y120320D01*
X583500D01*
X583000Y120820D01*
Y122320D01*
X583500Y122820D01*
X586000D01*
X586500Y123320D01*
Y124820D01*
X586000Y125320D01*
X583500D01*
X583000Y125820D01*
Y127320D01*
X583500Y127820D01*
X586000D01*
X586500Y128320D01*
Y129171D01*
X581000Y134671D01*
X557500D01*
X552171Y140000D01*
X531671D01*
X524500Y147171D01*
Y163146D01*
X510000Y177646D01*
Y193000D01*
X503000Y200000D01*
X489500D01*
X488000Y201500D01*
Y206500D01*
X485000Y209500D01*
X480500D01*
X479000Y211000D01*
Y214000D01*
X480250Y215250D01*
Y225749D01*
X478499Y227500D01*
X470000D01*
X466250Y231250D01*
Y255250D01*
X459500Y262000D01*
G01X461500Y268409D02*
X466591D01*
X467250Y267750D01*
X473470D01*
X483000Y258220D01*
Y228657D01*
X484250Y227407D01*
Y217078D01*
X490828Y210500D01*
X494501D01*
X501001Y204000D01*
X504658D01*
X514000Y194658D01*
Y179304D01*
X528500Y164804D01*
Y158501D01*
X532751Y154250D01*
X535533D01*
X540783Y149000D01*
X614500D01*
X622000Y141500D01*
G01X468500Y270000D02*
X468671Y270171D01*
X473171D01*
X484500Y258842D01*
Y229279D01*
X485750Y228029D01*
Y217750D01*
X491500Y212000D01*
X495123D01*
X501623Y205500D01*
X505280D01*
X515500Y195280D01*
Y179926D01*
X530000Y165426D01*
Y159123D01*
X533373Y155750D01*
X536155D01*
X541405Y150500D01*
X581500D01*
X585000Y154000D01*
X593000D01*
X595400Y151600D01*
X622000D01*
G01X492500Y226000D02*
X495500Y229000D01*
X500000D01*
X504000Y225000D01*
X508000D01*
X522000Y211000D01*
Y178621D01*
X537750Y162871D01*
Y160250D01*
X542000Y156000D01*
X580500D01*
X590000Y165500D01*
X606000D01*
X622000Y181500D01*
G01X497500Y226000D02*
Y217683D01*
X500000Y215183D01*
Y213001D01*
X517000Y196001D01*
Y181499D01*
X536250Y162249D01*
Y159249D01*
X541499Y154000D01*
X582500D01*
X588000Y159500D01*
X619500D01*
X622000Y162000D01*
G01X513200Y66000D02*
X522500Y75300D01*
Y102497D01*
X523000Y102997D01*
X524000D01*
X524500Y103497D01*
Y104997D01*
X524000Y105497D01*
X523000D01*
X522500Y105997D01*
Y107497D01*
X523000Y107997D01*
X524000D01*
X524500Y108497D01*
Y109997D01*
X524000Y110497D01*
X523000D01*
X522500Y110997D01*
Y114500D01*
G01X533000Y95000D02*
X530850Y97150D01*
Y113650D01*
X519000Y125500D01*
Y162988D01*
X504750Y177238D01*
Y190250D01*
X507000Y192500D01*
G01X533000Y99500D02*
Y105332D01*
X533500Y105832D01*
X539330D01*
X539830Y106332D01*
Y107832D01*
X539330Y108332D01*
X533500D01*
X533000Y108832D01*
Y110332D01*
X533500Y110832D01*
X537650D01*
X538150Y111332D01*
Y112832D01*
X537650Y113332D01*
X533500D01*
X533000Y113832D01*
Y115000D01*
X521000Y127000D01*
Y163817D01*
X507000Y177817D01*
Y188500D01*
G01X633000Y286500D02*
Y290000D01*
X612172Y310828D01*
X589672D01*
X585000Y315500D01*
X524987D01*
X515000Y325487D01*
Y334500D01*
X509000Y340500D01*
G01X633000Y267000D02*
X627500D01*
X625500Y269000D01*
Y293500D01*
X611000Y308000D01*
X588500D01*
X583000Y313500D01*
X524158D01*
X513000Y324658D01*
Y332000D01*
X504500Y340500D01*
G01X590500Y301500D02*
X587410Y298410D01*
Y295771D01*
X586389Y294750D01*
X582000D01*
X567250Y309500D01*
X538000D01*
X531000Y302500D01*
Y298000D01*
X528500Y295500D01*
X526000D01*
G01X590500Y301500D02*
X605920D01*
X623500Y283920D01*
Y254999D01*
X631500Y246999D01*
Y232501D01*
X629000Y230001D01*
Y217501D01*
X630500Y216001D01*
Y212545D01*
X625000Y207045D01*
Y186500D01*
X646000Y165500D01*
Y117500D01*
X643500Y115000D01*
Y95000D01*
X628500Y80000D01*
X599500D01*
X586750Y92750D01*
X572251D01*
X569451Y95550D01*
X543700D01*
X543250Y96000D01*
X541000D01*
G01X601902Y200100D02*
X587000Y185198D01*
Y184000D01*
G54D19*
G01X29922Y340080D02*
X31644Y338358D01*
G03X33473Y337600I1829J1828D01*
G01X37333D01*
G03X38131Y337931I-1J1129D01*
G01X38782Y338582D01*
G01X30346Y345046D02*
X31208Y345908D01*
G02X31671Y346100I463J-462D01*
G01X33733D01*
G02X34531Y345769I-1J-1129D01*
G01X34892Y345408D01*
G02X35238Y344572I-837J-836D01*
G01Y343150D01*
M02*
